(kicad_sch
	(version 20250114)
	(generator "eeschema")
	(generator_version "9.0")
	(paper "A3")
	(title_block
		(title "COM Express 7 Baseboard")
		(date "2025-02-04")
		(rev "1.1.2")
		(company "Antmicro Ltd")
		(comment 1 "www.antmicro.com")
	)
	(text "2x SFP+"
		(exclude_from_sim no)
		(at 204.724 21.844 0)
		(effects
			(font
				(size 2 2)
				(thickness 0.4)
				(bold yes)
			)
			(justify left bottom)
		)
	)
	(text "Address 0x75"
		(exclude_from_sim no)
		(at 191.77 274.32 0)
		(effects
			(font
				(size 1.27 1.27)
			)
			(justify left bottom)
		)
	)
	(junction
		(at 242.57 139.7)
		(diameter 0)
		(color 0 0 0 0)
	)
	(junction
		(at 250.19 76.2)
		(diameter 0)
		(color 0 0 0 0)
	)
	(junction
		(at 234.95 165.1)
		(diameter 0)
		(color 0 0 0 0)
	)
	(junction
		(at 250.19 119.38)
		(diameter 0)
		(color 0 0 0 0)
	)
	(junction
		(at 259.08 144.78)
		(diameter 0)
		(color 0 0 0 0)
	)
	(junction
		(at 247.65 167.64)
		(diameter 0)
		(color 0 0 0 0)
	)
	(junction
		(at 247.65 83.82)
		(diameter 0)
		(color 0 0 0 0)
	)
	(junction
		(at 250.19 35.56)
		(diameter 0)
		(color 0 0 0 0)
	)
	(junction
		(at 365.76 99.06)
		(diameter 0)
		(color 0 0 0 0)
	)
	(junction
		(at 241.3 35.56)
		(diameter 0)
		(color 0 0 0 0)
	)
	(junction
		(at 160.02 264.16)
		(diameter 0)
		(color 0 0 0 0)
	)
	(junction
		(at 234.95 139.7)
		(diameter 0)
		(color 0 0 0 0)
	)
	(junction
		(at 299.72 99.06)
		(diameter 0)
		(color 0 0 0 0)
	)
	(junction
		(at 250.19 55.88)
		(diameter 0)
		(color 0 0 0 0)
	)
	(junction
		(at 290.83 104.14)
		(diameter 0)
		(color 0 0 0 0)
	)
	(junction
		(at 228.6 238.76)
		(diameter 0)
		(color 0 0 0 0)
	)
	(junction
		(at 234.95 81.28)
		(diameter 0)
		(color 0 0 0 0)
	)
	(junction
		(at 330.2 99.06)
		(diameter 0)
		(color 0 0 0 0)
	)
	(junction
		(at 242.57 162.56)
		(diameter 0)
		(color 0 0 0 0)
	)
	(junction
		(at 303.53 99.06)
		(diameter 0)
		(color 0 0 0 0)
	)
	(junction
		(at 234.95 55.88)
		(diameter 0)
		(color 0 0 0 0)
	)
	(junction
		(at 250.19 139.7)
		(diameter 0)
		(color 0 0 0 0)
	)
	(junction
		(at 347.98 99.06)
		(diameter 0)
		(color 0 0 0 0)
	)
	(junction
		(at 303.53 113.03)
		(diameter 0)
		(color 0 0 0 0)
	)
	(junction
		(at 228.6 231.14)
		(diameter 0)
		(color 0 0 0 0)
	)
	(junction
		(at 259.08 55.88)
		(diameter 0)
		(color 0 0 0 0)
	)
	(junction
		(at 242.57 78.74)
		(diameter 0)
		(color 0 0 0 0)
	)
	(junction
		(at 356.87 99.06)
		(diameter 0)
		(color 0 0 0 0)
	)
	(junction
		(at 241.3 119.38)
		(diameter 0)
		(color 0 0 0 0)
	)
	(junction
		(at 339.09 99.06)
		(diameter 0)
		(color 0 0 0 0)
	)
	(junction
		(at 312.42 99.06)
		(diameter 0)
		(color 0 0 0 0)
	)
	(junction
		(at 259.08 139.7)
		(diameter 0)
		(color 0 0 0 0)
	)
	(junction
		(at 232.41 119.38)
		(diameter 0)
		(color 0 0 0 0)
	)
	(junction
		(at 242.57 55.88)
		(diameter 0)
		(color 0 0 0 0)
	)
	(junction
		(at 160.02 218.44)
		(diameter 0)
		(color 0 0 0 0)
	)
	(junction
		(at 168.91 218.44)
		(diameter 0)
		(color 0 0 0 0)
	)
	(junction
		(at 321.31 99.06)
		(diameter 0)
		(color 0 0 0 0)
	)
	(junction
		(at 250.19 160.02)
		(diameter 0)
		(color 0 0 0 0)
	)
	(junction
		(at 232.41 35.56)
		(diameter 0)
		(color 0 0 0 0)
	)
	(junction
		(at 259.08 60.96)
		(diameter 0)
		(color 0 0 0 0)
	)
	(junction
		(at 290.83 187.96)
		(diameter 0)
		(color 0 0 0 0)
	)
	(no_connect
		(at 203.2 256.54)
	)
	(no_connect
		(at 203.2 266.7)
	)
	(no_connect
		(at 203.2 269.24)
	)
	(no_connect
		(at 203.2 251.46)
	)
	(no_connect
		(at 203.2 261.62)
	)
	(no_connect
		(at 203.2 264.16)
	)
	(no_connect
		(at 203.2 254)
	)
	(no_connect
		(at 180.34 238.76)
	)
	(no_connect
		(at 203.2 259.08)
	)
	(bus_entry
		(at 147.32 236.22)
		(size -1.27 -1.27)
		(stroke
			(width 0)
			(type default)
		)
	)
	(bus_entry
		(at 176.53 69.85)
		(size 1.27 1.27)
		(stroke
			(width 0)
			(type default)
		)
	)
	(bus_entry
		(at 224.79 100.33)
		(size 1.27 1.27)
		(stroke
			(width 0)
			(type default)
		)
	)
	(bus_entry
		(at 224.79 186.69)
		(size 1.27 1.27)
		(stroke
			(width 0)
			(type default)
		)
	)
	(bus_entry
		(at 224.79 92.71)
		(size 1.27 1.27)
		(stroke
			(width 0)
			(type default)
		)
	)
	(bus_entry
		(at 224.79 176.53)
		(size 1.27 1.27)
		(stroke
			(width 0)
			(type default)
		)
	)
	(bus_entry
		(at 176.53 151.13)
		(size 1.27 1.27)
		(stroke
			(width 0)
			(type default)
		)
	)
	(bus_entry
		(at 224.79 102.87)
		(size 1.27 1.27)
		(stroke
			(width 0)
			(type default)
		)
	)
	(bus_entry
		(at 147.32 233.68)
		(size -1.27 -1.27)
		(stroke
			(width 0)
			(type default)
		)
	)
	(bus_entry
		(at 224.79 184.15)
		(size 1.27 1.27)
		(stroke
			(width 0)
			(type default)
		)
	)
	(bus_entry
		(at 224.79 95.25)
		(size 1.27 1.27)
		(stroke
			(width 0)
			(type default)
		)
	)
	(bus_entry
		(at 176.53 153.67)
		(size 1.27 1.27)
		(stroke
			(width 0)
			(type default)
		)
	)
	(bus_entry
		(at 224.79 179.07)
		(size 1.27 1.27)
		(stroke
			(width 0)
			(type default)
		)
	)
	(bus_entry
		(at 176.53 67.31)
		(size 1.27 1.27)
		(stroke
			(width 0)
			(type default)
		)
	)
	(wire
		(pts
			(xy 259.08 147.32) (xy 259.08 144.78)
		)
		(stroke
			(width 0)
			(type default)
		)
	)
	(wire
		(pts
			(xy 177.8 269.24) (xy 180.34 269.24)
		)
		(stroke
			(width 0)
			(type default)
		)
	)
	(wire
		(pts
			(xy 321.31 161.29) (xy 321.31 165.1)
		)
		(stroke
			(width 0)
			(type default)
		)
	)
	(wire
		(pts
			(xy 290.83 185.42) (xy 290.83 187.96)
		)
		(stroke
			(width 0)
			(type default)
		)
	)
	(wire
		(pts
			(xy 322.58 69.85) (xy 322.58 71.12)
		)
		(stroke
			(width 0)
			(type default)
		)
	)
	(bus
		(pts
			(xy 224.79 173.99) (xy 223.52 172.72)
		)
		(stroke
			(width 0)
			(type default)
		)
	)
	(wire
		(pts
			(xy 247.65 167.64) (xy 247.65 170.18)
		)
		(stroke
			(width 0)
			(type default)
		)
	)
	(wire
		(pts
			(xy 177.8 152.4) (xy 194.31 152.4)
		)
		(stroke
			(width 0)
			(type default)
		)
	)
	(wire
		(pts
			(xy 168.91 266.7) (xy 168.91 267.97)
		)
		(stroke
			(width 0)
			(type default)
		)
	)
	(wire
		(pts
			(xy 160.02 218.44) (xy 160.02 255.27)
		)
		(stroke
			(width 0)
			(type default)
		)
	)
	(bus
		(pts
			(xy 142.24 149.86) (xy 175.26 149.86)
		)
		(stroke
			(width 0)
			(type default)
		)
	)
	(wire
		(pts
			(xy 226.06 185.42) (xy 261.62 185.42)
		)
		(stroke
			(width 0)
			(type default)
		)
	)
	(wire
		(pts
			(xy 234.95 58.42) (xy 234.95 55.88)
		)
		(stroke
			(width 0)
			(type default)
		)
	)
	(bus
		(pts
			(xy 224.79 173.99) (xy 224.79 176.53)
		)
		(stroke
			(width 0)
			(type default)
		)
	)
	(wire
		(pts
			(xy 142.24 160.02) (xy 194.31 160.02)
		)
		(stroke
			(width 0)
			(type default)
		)
	)
	(wire
		(pts
			(xy 311.15 87.63) (xy 322.58 87.63)
		)
		(stroke
			(width 0)
			(type default)
		)
	)
	(wire
		(pts
			(xy 227.33 172.72) (xy 227.33 147.32)
		)
		(stroke
			(width 0)
			(type default)
		)
	)
	(bus
		(pts
			(xy 146.05 231.14) (xy 144.78 229.87)
		)
		(stroke
			(width 0)
			(type default)
		)
	)
	(wire
		(pts
			(xy 232.41 119.38) (xy 241.3 119.38)
		)
		(stroke
			(width 0)
			(type default)
		)
	)
	(wire
		(pts
			(xy 168.91 218.44) (xy 168.91 219.71)
		)
		(stroke
			(width 0)
			(type default)
		)
	)
	(wire
		(pts
			(xy 199.39 68.58) (xy 261.62 68.58)
		)
		(stroke
			(width 0)
			(type default)
		)
	)
	(wire
		(pts
			(xy 173.99 233.68) (xy 180.34 233.68)
		)
		(stroke
			(width 0)
			(type default)
		)
	)
	(wire
		(pts
			(xy 322.58 85.09) (xy 322.58 87.63)
		)
		(stroke
			(width 0)
			(type default)
		)
	)
	(wire
		(pts
			(xy 232.41 35.56) (xy 232.41 36.83)
		)
		(stroke
			(width 0)
			(type default)
		)
	)
	(wire
		(pts
			(xy 226.06 101.6) (xy 261.62 101.6)
		)
		(stroke
			(width 0)
			(type default)
		)
	)
	(wire
		(pts
			(xy 160.02 264.16) (xy 160.02 267.97)
		)
		(stroke
			(width 0)
			(type default)
		)
	)
	(wire
		(pts
			(xy 242.57 58.42) (xy 242.57 55.88)
		)
		(stroke
			(width 0)
			(type default)
		)
	)
	(wire
		(pts
			(xy 147.32 233.68) (xy 168.91 233.68)
		)
		(stroke
			(width 0)
			(type default)
		)
	)
	(wire
		(pts
			(xy 243.84 83.82) (xy 247.65 83.82)
		)
		(stroke
			(width 0)
			(type default)
		)
	)
	(bus
		(pts
			(xy 146.05 231.14) (xy 146.05 232.41)
		)
		(stroke
			(width 0)
			(type default)
		)
	)
	(wire
		(pts
			(xy 250.19 119.38) (xy 259.08 119.38)
		)
		(stroke
			(width 0)
			(type default)
		)
	)
	(wire
		(pts
			(xy 199.39 152.4) (xy 261.62 152.4)
		)
		(stroke
			(width 0)
			(type default)
		)
	)
	(wire
		(pts
			(xy 177.8 269.24) (xy 177.8 274.32)
		)
		(stroke
			(width 0)
			(type default)
		)
	)
	(bus
		(pts
			(xy 224.79 90.17) (xy 224.79 92.71)
		)
		(stroke
			(width 0)
			(type default)
		)
	)
	(wire
		(pts
			(xy 241.3 78.74) (xy 242.57 78.74)
		)
		(stroke
			(width 0)
			(type default)
		)
	)
	(wire
		(pts
			(xy 312.42 99.06) (xy 321.31 99.06)
		)
		(stroke
			(width 0)
			(type default)
		)
	)
	(bus
		(pts
			(xy 176.53 67.31) (xy 175.26 66.04)
		)
		(stroke
			(width 0)
			(type default)
		)
	)
	(wire
		(pts
			(xy 168.91 266.7) (xy 180.34 266.7)
		)
		(stroke
			(width 0)
			(type default)
		)
	)
	(wire
		(pts
			(xy 241.3 162.56) (xy 242.57 162.56)
		)
		(stroke
			(width 0)
			(type default)
		)
	)
	(wire
		(pts
			(xy 347.98 109.22) (xy 347.98 114.3)
		)
		(stroke
			(width 0)
			(type default)
		)
	)
	(wire
		(pts
			(xy 142.24 105.41) (xy 152.4 105.41)
		)
		(stroke
			(width 0)
			(type default)
		)
	)
	(wire
		(pts
			(xy 344.17 76.2) (xy 344.17 80.01)
		)
		(stroke
			(width 0)
			(type default)
		)
	)
	(wire
		(pts
			(xy 199.39 71.12) (xy 261.62 71.12)
		)
		(stroke
			(width 0)
			(type default)
		)
	)
	(wire
		(pts
			(xy 250.19 76.2) (xy 261.62 76.2)
		)
		(stroke
			(width 0)
			(type default)
		)
	)
	(wire
		(pts
			(xy 243.84 167.64) (xy 247.65 167.64)
		)
		(stroke
			(width 0)
			(type default)
		)
	)
	(wire
		(pts
			(xy 242.57 147.32) (xy 242.57 162.56)
		)
		(stroke
			(width 0)
			(type default)
		)
	)
	(wire
		(pts
			(xy 234.95 81.28) (xy 261.62 81.28)
		)
		(stroke
			(width 0)
			(type default)
		)
	)
	(wire
		(pts
			(xy 234.95 139.7) (xy 242.57 139.7)
		)
		(stroke
			(width 0)
			(type default)
		)
	)
	(wire
		(pts
			(xy 312.42 109.22) (xy 312.42 114.3)
		)
		(stroke
			(width 0)
			(type default)
		)
	)
	(wire
		(pts
			(xy 142.24 76.2) (xy 194.31 76.2)
		)
		(stroke
			(width 0)
			(type default)
		)
	)
	(wire
		(pts
			(xy 339.09 99.06) (xy 347.98 99.06)
		)
		(stroke
			(width 0)
			(type default)
		)
	)
	(wire
		(pts
			(xy 303.53 99.06) (xy 312.42 99.06)
		)
		(stroke
			(width 0)
			(type default)
		)
	)
	(wire
		(pts
			(xy 234.95 147.32) (xy 234.95 165.1)
		)
		(stroke
			(width 0)
			(type default)
		)
	)
	(wire
		(pts
			(xy 177.8 154.94) (xy 194.31 154.94)
		)
		(stroke
			(width 0)
			(type default)
		)
	)
	(wire
		(pts
			(xy 168.91 218.44) (xy 177.8 218.44)
		)
		(stroke
			(width 0)
			(type default)
		)
	)
	(wire
		(pts
			(xy 177.8 71.12) (xy 194.31 71.12)
		)
		(stroke
			(width 0)
			(type default)
		)
	)
	(wire
		(pts
			(xy 177.8 68.58) (xy 194.31 68.58)
		)
		(stroke
			(width 0)
			(type default)
		)
	)
	(wire
		(pts
			(xy 232.41 34.29) (xy 232.41 35.56)
		)
		(stroke
			(width 0)
			(type default)
		)
	)
	(wire
		(pts
			(xy 303.53 104.14) (xy 303.53 99.06)
		)
		(stroke
			(width 0)
			(type default)
		)
	)
	(wire
		(pts
			(xy 344.17 69.85) (xy 344.17 71.12)
		)
		(stroke
			(width 0)
			(type default)
		)
	)
	(wire
		(pts
			(xy 241.3 43.18) (xy 241.3 41.91)
		)
		(stroke
			(width 0)
			(type default)
		)
	)
	(wire
		(pts
			(xy 160.02 218.44) (xy 168.91 218.44)
		)
		(stroke
			(width 0)
			(type default)
		)
	)
	(wire
		(pts
			(xy 242.57 63.5) (xy 242.57 78.74)
		)
		(stroke
			(width 0)
			(type default)
		)
	)
	(wire
		(pts
			(xy 309.88 165.1) (xy 321.31 165.1)
		)
		(stroke
			(width 0)
			(type default)
		)
	)
	(wire
		(pts
			(xy 247.65 170.18) (xy 251.46 170.18)
		)
		(stroke
			(width 0)
			(type default)
		)
	)
	(wire
		(pts
			(xy 259.08 144.78) (xy 261.62 144.78)
		)
		(stroke
			(width 0)
			(type default)
		)
	)
	(wire
		(pts
			(xy 242.57 78.74) (xy 261.62 78.74)
		)
		(stroke
			(width 0)
			(type default)
		)
	)
	(wire
		(pts
			(xy 242.57 55.88) (xy 250.19 55.88)
		)
		(stroke
			(width 0)
			(type default)
		)
	)
	(wire
		(pts
			(xy 250.19 36.83) (xy 250.19 35.56)
		)
		(stroke
			(width 0)
			(type default)
		)
	)
	(wire
		(pts
			(xy 256.54 83.82) (xy 261.62 83.82)
		)
		(stroke
			(width 0)
			(type default)
		)
	)
	(wire
		(pts
			(xy 342.9 153.67) (xy 342.9 156.21)
		)
		(stroke
			(width 0)
			(type default)
		)
	)
	(wire
		(pts
			(xy 199.39 154.94) (xy 261.62 154.94)
		)
		(stroke
			(width 0)
			(type default)
		)
	)
	(wire
		(pts
			(xy 289.56 99.06) (xy 299.72 99.06)
		)
		(stroke
			(width 0)
			(type default)
		)
	)
	(wire
		(pts
			(xy 250.19 120.65) (xy 250.19 119.38)
		)
		(stroke
			(width 0)
			(type default)
		)
	)
	(wire
		(pts
			(xy 232.41 118.11) (xy 232.41 119.38)
		)
		(stroke
			(width 0)
			(type default)
		)
	)
	(wire
		(pts
			(xy 227.33 55.88) (xy 227.33 58.42)
		)
		(stroke
			(width 0)
			(type default)
		)
	)
	(wire
		(pts
			(xy 321.31 147.32) (xy 321.31 148.59)
		)
		(stroke
			(width 0)
			(type default)
		)
	)
	(bus
		(pts
			(xy 176.53 151.13) (xy 175.26 149.86)
		)
		(stroke
			(width 0)
			(type default)
		)
	)
	(wire
		(pts
			(xy 331.47 165.1) (xy 342.9 165.1)
		)
		(stroke
			(width 0)
			(type default)
		)
	)
	(wire
		(pts
			(xy 203.2 228.6) (xy 219.71 228.6)
		)
		(stroke
			(width 0)
			(type default)
		)
	)
	(wire
		(pts
			(xy 232.41 35.56) (xy 241.3 35.56)
		)
		(stroke
			(width 0)
			(type default)
		)
	)
	(wire
		(pts
			(xy 342.9 161.29) (xy 342.9 165.1)
		)
		(stroke
			(width 0)
			(type default)
		)
	)
	(wire
		(pts
			(xy 365.76 99.06) (xy 365.76 104.14)
		)
		(stroke
			(width 0)
			(type default)
		)
	)
	(wire
		(pts
			(xy 374.65 109.22) (xy 374.65 114.3)
		)
		(stroke
			(width 0)
			(type default)
		)
	)
	(wire
		(pts
			(xy 250.19 160.02) (xy 250.19 147.32)
		)
		(stroke
			(width 0)
			(type default)
		)
	)
	(wire
		(pts
			(xy 321.31 109.22) (xy 321.31 114.3)
		)
		(stroke
			(width 0)
			(type default)
		)
	)
	(wire
		(pts
			(xy 312.42 99.06) (xy 312.42 104.14)
		)
		(stroke
			(width 0)
			(type default)
		)
	)
	(wire
		(pts
			(xy 299.72 104.14) (xy 299.72 99.06)
		)
		(stroke
			(width 0)
			(type default)
		)
	)
	(wire
		(pts
			(xy 342.9 147.32) (xy 342.9 148.59)
		)
		(stroke
			(width 0)
			(type default)
		)
	)
	(wire
		(pts
			(xy 243.84 168.91) (xy 243.84 167.64)
		)
		(stroke
			(width 0)
			(type default)
		)
	)
	(bus
		(pts
			(xy 142.24 229.87) (xy 144.78 229.87)
		)
		(stroke
			(width 0)
			(type default)
		)
	)
	(wire
		(pts
			(xy 250.19 35.56) (xy 241.3 35.56)
		)
		(stroke
			(width 0)
			(type default)
		)
	)
	(bus
		(pts
			(xy 142.24 88.9) (xy 152.4 88.9)
		)
		(stroke
			(width 0)
			(type default)
		)
	)
	(wire
		(pts
			(xy 203.2 241.3) (xy 219.71 241.3)
		)
		(stroke
			(width 0)
			(type default)
		)
	)
	(wire
		(pts
			(xy 160.02 264.16) (xy 180.34 264.16)
		)
		(stroke
			(width 0)
			(type default)
		)
	)
	(bus
		(pts
			(xy 224.79 179.07) (xy 224.79 184.15)
		)
		(stroke
			(width 0)
			(type default)
		)
	)
	(wire
		(pts
			(xy 224.79 241.3) (xy 228.6 241.3)
		)
		(stroke
			(width 0)
			(type default)
		)
	)
	(wire
		(pts
			(xy 227.33 172.72) (xy 261.62 172.72)
		)
		(stroke
			(width 0)
			(type default)
		)
	)
	(wire
		(pts
			(xy 242.57 142.24) (xy 242.57 139.7)
		)
		(stroke
			(width 0)
			(type default)
		)
	)
	(wire
		(pts
			(xy 374.65 99.06) (xy 374.65 104.14)
		)
		(stroke
			(width 0)
			(type default)
		)
	)
	(wire
		(pts
			(xy 250.19 55.88) (xy 259.08 55.88)
		)
		(stroke
			(width 0)
			(type default)
		)
	)
	(wire
		(pts
			(xy 250.19 160.02) (xy 261.62 160.02)
		)
		(stroke
			(width 0)
			(type default)
		)
	)
	(wire
		(pts
			(xy 339.09 99.06) (xy 339.09 104.14)
		)
		(stroke
			(width 0)
			(type default)
		)
	)
	(wire
		(pts
			(xy 365.76 109.22) (xy 365.76 114.3)
		)
		(stroke
			(width 0)
			(type default)
		)
	)
	(wire
		(pts
			(xy 203.2 238.76) (xy 219.71 238.76)
		)
		(stroke
			(width 0)
			(type default)
		)
	)
	(wire
		(pts
			(xy 227.33 139.7) (xy 227.33 142.24)
		)
		(stroke
			(width 0)
			(type default)
		)
	)
	(wire
		(pts
			(xy 241.3 35.56) (xy 241.3 36.83)
		)
		(stroke
			(width 0)
			(type default)
		)
	)
	(wire
		(pts
			(xy 224.79 233.68) (xy 228.6 233.68)
		)
		(stroke
			(width 0)
			(type default)
		)
	)
	(wire
		(pts
			(xy 321.31 153.67) (xy 321.31 156.21)
		)
		(stroke
			(width 0)
			(type default)
		)
	)
	(wire
		(pts
			(xy 250.19 43.18) (xy 250.19 41.91)
		)
		(stroke
			(width 0)
			(type default)
		)
	)
	(wire
		(pts
			(xy 241.3 119.38) (xy 241.3 120.65)
		)
		(stroke
			(width 0)
			(type default)
		)
	)
	(wire
		(pts
			(xy 224.79 228.6) (xy 241.3 228.6)
		)
		(stroke
			(width 0)
			(type default)
		)
	)
	(wire
		(pts
			(xy 226.06 93.98) (xy 261.62 93.98)
		)
		(stroke
			(width 0)
			(type default)
		)
	)
	(wire
		(pts
			(xy 330.2 99.06) (xy 330.2 104.14)
		)
		(stroke
			(width 0)
			(type default)
		)
	)
	(wire
		(pts
			(xy 226.06 104.14) (xy 261.62 104.14)
		)
		(stroke
			(width 0)
			(type default)
		)
	)
	(wire
		(pts
			(xy 243.84 85.09) (xy 243.84 83.82)
		)
		(stroke
			(width 0)
			(type default)
		)
	)
	(wire
		(pts
			(xy 160.02 273.05) (xy 160.02 274.32)
		)
		(stroke
			(width 0)
			(type default)
		)
	)
	(wire
		(pts
			(xy 227.33 88.9) (xy 227.33 63.5)
		)
		(stroke
			(width 0)
			(type default)
		)
	)
	(wire
		(pts
			(xy 228.6 238.76) (xy 241.3 238.76)
		)
		(stroke
			(width 0)
			(type default)
		)
	)
	(bus
		(pts
			(xy 146.05 232.41) (xy 146.05 234.95)
		)
		(stroke
			(width 0)
			(type default)
		)
	)
	(wire
		(pts
			(xy 289.56 187.96) (xy 290.83 187.96)
		)
		(stroke
			(width 0)
			(type default)
		)
	)
	(wire
		(pts
			(xy 247.65 86.36) (xy 251.46 86.36)
		)
		(stroke
			(width 0)
			(type default)
		)
	)
	(wire
		(pts
			(xy 299.72 99.06) (xy 303.53 99.06)
		)
		(stroke
			(width 0)
			(type default)
		)
	)
	(wire
		(pts
			(xy 224.79 238.76) (xy 228.6 238.76)
		)
		(stroke
			(width 0)
			(type default)
		)
	)
	(wire
		(pts
			(xy 321.31 99.06) (xy 321.31 104.14)
		)
		(stroke
			(width 0)
			(type default)
		)
	)
	(wire
		(pts
			(xy 303.53 113.03) (xy 303.53 114.3)
		)
		(stroke
			(width 0)
			(type default)
		)
	)
	(wire
		(pts
			(xy 147.32 236.22) (xy 168.91 236.22)
		)
		(stroke
			(width 0)
			(type default)
		)
	)
	(wire
		(pts
			(xy 203.2 236.22) (xy 219.71 236.22)
		)
		(stroke
			(width 0)
			(type default)
		)
	)
	(wire
		(pts
			(xy 250.19 76.2) (xy 250.19 63.5)
		)
		(stroke
			(width 0)
			(type default)
		)
	)
	(wire
		(pts
			(xy 203.2 233.68) (xy 219.71 233.68)
		)
		(stroke
			(width 0)
			(type default)
		)
	)
	(wire
		(pts
			(xy 299.72 113.03) (xy 299.72 109.22)
		)
		(stroke
			(width 0)
			(type default)
		)
	)
	(wire
		(pts
			(xy 173.99 251.46) (xy 180.34 251.46)
		)
		(stroke
			(width 0)
			(type default)
		)
	)
	(wire
		(pts
			(xy 299.72 113.03) (xy 303.53 113.03)
		)
		(stroke
			(width 0)
			(type default)
		)
	)
	(wire
		(pts
			(xy 322.58 76.2) (xy 322.58 80.01)
		)
		(stroke
			(width 0)
			(type default)
		)
	)
	(wire
		(pts
			(xy 224.79 236.22) (xy 241.3 236.22)
		)
		(stroke
			(width 0)
			(type default)
		)
	)
	(wire
		(pts
			(xy 233.68 81.28) (xy 234.95 81.28)
		)
		(stroke
			(width 0)
			(type default)
		)
	)
	(wire
		(pts
			(xy 344.17 85.09) (xy 344.17 87.63)
		)
		(stroke
			(width 0)
			(type default)
		)
	)
	(wire
		(pts
			(xy 290.83 101.6) (xy 290.83 104.14)
		)
		(stroke
			(width 0)
			(type default)
		)
	)
	(wire
		(pts
			(xy 226.06 177.8) (xy 261.62 177.8)
		)
		(stroke
			(width 0)
			(type default)
		)
	)
	(wire
		(pts
			(xy 228.6 241.3) (xy 228.6 238.76)
		)
		(stroke
			(width 0)
			(type default)
		)
	)
	(bus
		(pts
			(xy 224.79 90.17) (xy 223.52 88.9)
		)
		(stroke
			(width 0)
			(type default)
		)
	)
	(bus
		(pts
			(xy 176.53 151.13) (xy 176.53 153.67)
		)
		(stroke
			(width 0)
			(type default)
		)
	)
	(wire
		(pts
			(xy 232.41 43.18) (xy 232.41 41.91)
		)
		(stroke
			(width 0)
			(type default)
		)
	)
	(wire
		(pts
			(xy 226.06 187.96) (xy 261.62 187.96)
		)
		(stroke
			(width 0)
			(type default)
		)
	)
	(wire
		(pts
			(xy 142.24 251.46) (xy 168.91 251.46)
		)
		(stroke
			(width 0)
			(type default)
		)
	)
	(wire
		(pts
			(xy 233.68 165.1) (xy 234.95 165.1)
		)
		(stroke
			(width 0)
			(type default)
		)
	)
	(wire
		(pts
			(xy 256.54 170.18) (xy 261.62 170.18)
		)
		(stroke
			(width 0)
			(type default)
		)
	)
	(wire
		(pts
			(xy 177.8 228.6) (xy 180.34 228.6)
		)
		(stroke
			(width 0)
			(type default)
		)
	)
	(wire
		(pts
			(xy 199.39 76.2) (xy 250.19 76.2)
		)
		(stroke
			(width 0)
			(type default)
		)
	)
	(wire
		(pts
			(xy 234.95 165.1) (xy 261.62 165.1)
		)
		(stroke
			(width 0)
			(type default)
		)
	)
	(wire
		(pts
			(xy 160.02 260.35) (xy 160.02 264.16)
		)
		(stroke
			(width 0)
			(type default)
		)
	)
	(bus
		(pts
			(xy 224.79 100.33) (xy 224.79 102.87)
		)
		(stroke
			(width 0)
			(type default)
		)
	)
	(wire
		(pts
			(xy 242.57 139.7) (xy 250.19 139.7)
		)
		(stroke
			(width 0)
			(type default)
		)
	)
	(wire
		(pts
			(xy 227.33 88.9) (xy 261.62 88.9)
		)
		(stroke
			(width 0)
			(type default)
		)
	)
	(wire
		(pts
			(xy 347.98 99.06) (xy 356.87 99.06)
		)
		(stroke
			(width 0)
			(type default)
		)
	)
	(wire
		(pts
			(xy 142.24 189.23) (xy 152.4 189.23)
		)
		(stroke
			(width 0)
			(type default)
		)
	)
	(wire
		(pts
			(xy 321.31 99.06) (xy 330.2 99.06)
		)
		(stroke
			(width 0)
			(type default)
		)
	)
	(wire
		(pts
			(xy 199.39 160.02) (xy 250.19 160.02)
		)
		(stroke
			(width 0)
			(type default)
		)
	)
	(wire
		(pts
			(xy 250.19 58.42) (xy 250.19 55.88)
		)
		(stroke
			(width 0)
			(type default)
		)
	)
	(wire
		(pts
			(xy 227.33 139.7) (xy 234.95 139.7)
		)
		(stroke
			(width 0)
			(type default)
		)
	)
	(wire
		(pts
			(xy 259.08 60.96) (xy 261.62 60.96)
		)
		(stroke
			(width 0)
			(type default)
		)
	)
	(bus
		(pts
			(xy 208.28 172.72) (xy 223.52 172.72)
		)
		(stroke
			(width 0)
			(type default)
		)
	)
	(bus
		(pts
			(xy 176.53 67.31) (xy 176.53 69.85)
		)
		(stroke
			(width 0)
			(type default)
		)
	)
	(wire
		(pts
			(xy 227.33 55.88) (xy 234.95 55.88)
		)
		(stroke
			(width 0)
			(type default)
		)
	)
	(wire
		(pts
			(xy 356.87 99.06) (xy 356.87 104.14)
		)
		(stroke
			(width 0)
			(type default)
		)
	)
	(wire
		(pts
			(xy 234.95 142.24) (xy 234.95 139.7)
		)
		(stroke
			(width 0)
			(type default)
		)
	)
	(wire
		(pts
			(xy 259.08 119.38) (xy 259.08 139.7)
		)
		(stroke
			(width 0)
			(type default)
		)
	)
	(wire
		(pts
			(xy 177.8 218.44) (xy 177.8 228.6)
		)
		(stroke
			(width 0)
			(type default)
		)
	)
	(wire
		(pts
			(xy 256.54 167.64) (xy 261.62 167.64)
		)
		(stroke
			(width 0)
			(type default)
		)
	)
	(wire
		(pts
			(xy 247.65 167.64) (xy 251.46 167.64)
		)
		(stroke
			(width 0)
			(type default)
		)
	)
	(wire
		(pts
			(xy 228.6 233.68) (xy 228.6 231.14)
		)
		(stroke
			(width 0)
			(type default)
		)
	)
	(wire
		(pts
			(xy 259.08 139.7) (xy 259.08 144.78)
		)
		(stroke
			(width 0)
			(type default)
		)
	)
	(wire
		(pts
			(xy 332.74 87.63) (xy 344.17 87.63)
		)
		(stroke
			(width 0)
			(type default)
		)
	)
	(wire
		(pts
			(xy 250.19 35.56) (xy 259.08 35.56)
		)
		(stroke
			(width 0)
			(type default)
		)
	)
	(wire
		(pts
			(xy 168.91 273.05) (xy 168.91 274.32)
		)
		(stroke
			(width 0)
			(type default)
		)
	)
	(wire
		(pts
			(xy 290.83 104.14) (xy 290.83 105.41)
		)
		(stroke
			(width 0)
			(type default)
		)
	)
	(wire
		(pts
			(xy 289.56 101.6) (xy 290.83 101.6)
		)
		(stroke
			(width 0)
			(type default)
		)
	)
	(wire
		(pts
			(xy 234.95 55.88) (xy 242.57 55.88)
		)
		(stroke
			(width 0)
			(type default)
		)
	)
	(wire
		(pts
			(xy 203.2 231.14) (xy 219.71 231.14)
		)
		(stroke
			(width 0)
			(type default)
		)
	)
	(wire
		(pts
			(xy 339.09 109.22) (xy 339.09 114.3)
		)
		(stroke
			(width 0)
			(type default)
		)
	)
	(wire
		(pts
			(xy 228.6 231.14) (xy 241.3 231.14)
		)
		(stroke
			(width 0)
			(type default)
		)
	)
	(wire
		(pts
			(xy 234.95 63.5) (xy 234.95 81.28)
		)
		(stroke
			(width 0)
			(type default)
		)
	)
	(wire
		(pts
			(xy 226.06 180.34) (xy 261.62 180.34)
		)
		(stroke
			(width 0)
			(type default)
		)
	)
	(wire
		(pts
			(xy 303.53 113.03) (xy 303.53 109.22)
		)
		(stroke
			(width 0)
			(type default)
		)
	)
	(wire
		(pts
			(xy 160.02 217.17) (xy 160.02 218.44)
		)
		(stroke
			(width 0)
			(type default)
		)
	)
	(bus
		(pts
			(xy 142.24 66.04) (xy 175.26 66.04)
		)
		(stroke
			(width 0)
			(type default)
		)
	)
	(wire
		(pts
			(xy 247.65 83.82) (xy 247.65 86.36)
		)
		(stroke
			(width 0)
			(type default)
		)
	)
	(wire
		(pts
			(xy 330.2 109.22) (xy 330.2 114.3)
		)
		(stroke
			(width 0)
			(type default)
		)
	)
	(wire
		(pts
			(xy 259.08 63.5) (xy 259.08 60.96)
		)
		(stroke
			(width 0)
			(type default)
		)
	)
	(wire
		(pts
			(xy 289.56 185.42) (xy 290.83 185.42)
		)
		(stroke
			(width 0)
			(type default)
		)
	)
	(wire
		(pts
			(xy 242.57 162.56) (xy 261.62 162.56)
		)
		(stroke
			(width 0)
			(type default)
		)
	)
	(wire
		(pts
			(xy 356.87 109.22) (xy 356.87 114.3)
		)
		(stroke
			(width 0)
			(type default)
		)
	)
	(bus
		(pts
			(xy 142.24 186.69) (xy 152.4 186.69)
		)
		(stroke
			(width 0)
			(type default)
		)
	)
	(bus
		(pts
			(xy 224.79 179.07) (xy 224.79 176.53)
		)
		(stroke
			(width 0)
			(type default)
		)
	)
	(wire
		(pts
			(xy 250.19 142.24) (xy 250.19 139.7)
		)
		(stroke
			(width 0)
			(type default)
		)
	)
	(bus
		(pts
			(xy 142.24 172.72) (xy 152.4 172.72)
		)
		(stroke
			(width 0)
			(type default)
		)
	)
	(wire
		(pts
			(xy 256.54 86.36) (xy 261.62 86.36)
		)
		(stroke
			(width 0)
			(type default)
		)
	)
	(bus
		(pts
			(xy 224.79 95.25) (xy 224.79 100.33)
		)
		(stroke
			(width 0)
			(type default)
		)
	)
	(wire
		(pts
			(xy 261.62 147.32) (xy 259.08 147.32)
		)
		(stroke
			(width 0)
			(type default)
		)
	)
	(wire
		(pts
			(xy 226.06 96.52) (xy 261.62 96.52)
		)
		(stroke
			(width 0)
			(type default)
		)
	)
	(wire
		(pts
			(xy 247.65 83.82) (xy 251.46 83.82)
		)
		(stroke
			(width 0)
			(type default)
		)
	)
	(wire
		(pts
			(xy 259.08 55.88) (xy 259.08 60.96)
		)
		(stroke
			(width 0)
			(type default)
		)
	)
	(bus
		(pts
			(xy 224.79 95.25) (xy 224.79 92.71)
		)
		(stroke
			(width 0)
			(type default)
		)
	)
	(wire
		(pts
			(xy 250.19 119.38) (xy 241.3 119.38)
		)
		(stroke
			(width 0)
			(type default)
		)
	)
	(wire
		(pts
			(xy 259.08 35.56) (xy 259.08 55.88)
		)
		(stroke
			(width 0)
			(type default)
		)
	)
	(bus
		(pts
			(xy 142.24 102.87) (xy 152.4 102.87)
		)
		(stroke
			(width 0)
			(type default)
		)
	)
	(wire
		(pts
			(xy 347.98 99.06) (xy 347.98 104.14)
		)
		(stroke
			(width 0)
			(type default)
		)
	)
	(wire
		(pts
			(xy 173.99 236.22) (xy 180.34 236.22)
		)
		(stroke
			(width 0)
			(type default)
		)
	)
	(wire
		(pts
			(xy 290.83 187.96) (xy 290.83 189.23)
		)
		(stroke
			(width 0)
			(type default)
		)
	)
	(wire
		(pts
			(xy 289.56 104.14) (xy 290.83 104.14)
		)
		(stroke
			(width 0)
			(type default)
		)
	)
	(wire
		(pts
			(xy 330.2 99.06) (xy 339.09 99.06)
		)
		(stroke
			(width 0)
			(type default)
		)
	)
	(wire
		(pts
			(xy 365.76 99.06) (xy 374.65 99.06)
		)
		(stroke
			(width 0)
			(type default)
		)
	)
	(bus
		(pts
			(xy 224.79 184.15) (xy 224.79 186.69)
		)
		(stroke
			(width 0)
			(type default)
		)
	)
	(wire
		(pts
			(xy 224.79 231.14) (xy 228.6 231.14)
		)
		(stroke
			(width 0)
			(type default)
		)
	)
	(bus
		(pts
			(xy 208.28 88.9) (xy 223.52 88.9)
		)
		(stroke
			(width 0)
			(type default)
		)
	)
	(wire
		(pts
			(xy 261.62 63.5) (xy 259.08 63.5)
		)
		(stroke
			(width 0)
			(type default)
		)
	)
	(wire
		(pts
			(xy 232.41 119.38) (xy 232.41 120.65)
		)
		(stroke
			(width 0)
			(type default)
		)
	)
	(wire
		(pts
			(xy 250.19 139.7) (xy 259.08 139.7)
		)
		(stroke
			(width 0)
			(type default)
		)
	)
	(wire
		(pts
			(xy 356.87 99.06) (xy 365.76 99.06)
		)
		(stroke
			(width 0)
			(type default)
		)
	)
	(label "SFP1_LEDY"
		(at 309.88 165.1 0)
		(effects
			(font
				(size 1.27 1.27)
			)
			(justify left bottom)
		)
	)
	(label "SFI0.TX-"
		(at 236.22 96.52 180)
		(effects
			(font
				(size 1.27 1.27)
			)
			(justify right bottom)
		)
	)
	(label "SFP1_LEDY"
		(at 241.3 236.22 180)
		(effects
			(font
				(size 1.27 1.27)
			)
			(justify right bottom)
		)
	)
	(label "SFP0_LEDY"
		(at 311.15 87.63 0)
		(effects
			(font
				(size 1.27 1.27)
			)
			(justify left bottom)
		)
	)
	(label "~{LED0_2}"
		(at 204.47 233.68 0)
		(effects
			(font
				(size 1.27 1.27)
			)
			(justify left bottom)
		)
	)
	(label "SFI1.TX+"
		(at 236.22 177.8 180)
		(effects
			(font
				(size 1.27 1.27)
			)
			(justify right bottom)
		)
	)
	(label "I2C_{SFP0}.SCL"
		(at 177.8 71.12 0)
		(effects
			(font
				(size 1.27 1.27)
			)
			(justify left bottom)
		)
	)
	(label "SFI0{SFI}"
		(at 213.36 88.9 0)
		(effects
			(font
				(size 1.27 1.27)
			)
			(justify left bottom)
		)
	)
	(label "~{LED1_1}"
		(at 204.47 238.76 0)
		(effects
			(font
				(size 1.27 1.27)
			)
			(justify left bottom)
		)
	)
	(label "SFP0_LEDY"
		(at 241.3 228.6 180)
		(effects
			(font
				(size 1.27 1.27)
			)
			(justify right bottom)
		)
	)
	(label "SFP0_LEDG"
		(at 332.74 87.63 0)
		(effects
			(font
				(size 1.27 1.27)
			)
			(justify left bottom)
		)
	)
	(label "SFI0.TX+"
		(at 236.22 93.98 180)
		(effects
			(font
				(size 1.27 1.27)
			)
			(justify right bottom)
		)
	)
	(label "I2C_{SFP1}.SDA"
		(at 177.8 152.4 0)
		(effects
			(font
				(size 1.27 1.27)
			)
			(justify left bottom)
		)
	)
	(label "SFI0.RX-"
		(at 236.22 104.14 180)
		(effects
			(font
				(size 1.27 1.27)
			)
			(justify right bottom)
		)
	)
	(label "SH"
		(at 299.72 99.06 180)
		(effects
			(font
				(size 1.27 1.27)
			)
			(justify right bottom)
		)
	)
	(label "SDA1"
		(at 255.27 152.4 0)
		(effects
			(font
				(size 1.27 1.27)
			)
			(justify left bottom)
		)
	)
	(label "I2C_{SFP0}.SDA"
		(at 177.8 68.58 0)
		(effects
			(font
				(size 1.27 1.27)
			)
			(justify left bottom)
		)
	)
	(label "I2C_{SFP1}.SCL"
		(at 177.8 154.94 0)
		(effects
			(font
				(size 1.27 1.27)
			)
			(justify left bottom)
		)
	)
	(label "I2C_{LED}.SCL"
		(at 148.59 236.22 0)
		(effects
			(font
				(size 1.27 1.27)
			)
			(justify left bottom)
		)
	)
	(label "SFI1.TX-"
		(at 236.22 180.34 180)
		(effects
			(font
				(size 1.27 1.27)
			)
			(justify right bottom)
		)
	)
	(label "SFP1_LEDG"
		(at 241.3 238.76 180)
		(effects
			(font
				(size 1.27 1.27)
			)
			(justify right bottom)
		)
	)
	(label "SFI1{SFI}"
		(at 213.36 172.72 0)
		(effects
			(font
				(size 1.27 1.27)
			)
			(justify left bottom)
		)
	)
	(label "SFI1.RX-"
		(at 236.22 187.96 180)
		(effects
			(font
				(size 1.27 1.27)
			)
			(justify right bottom)
		)
	)
	(label "I2C_{LED}.SDA"
		(at 148.59 233.68 0)
		(effects
			(font
				(size 1.27 1.27)
			)
			(justify left bottom)
		)
	)
	(label "SCL0"
		(at 255.27 71.12 0)
		(effects
			(font
				(size 1.27 1.27)
			)
			(justify left bottom)
		)
	)
	(label "SFI1.RX+"
		(at 236.22 185.42 180)
		(effects
			(font
				(size 1.27 1.27)
			)
			(justify right bottom)
		)
	)
	(label "~{LED0_1}"
		(at 204.47 231.14 0)
		(effects
			(font
				(size 1.27 1.27)
			)
			(justify left bottom)
		)
	)
	(label "~{LED1_0}"
		(at 204.47 236.22 0)
		(effects
			(font
				(size 1.27 1.27)
			)
			(justify left bottom)
		)
	)
	(label "~{LED1_2}"
		(at 204.47 241.3 0)
		(effects
			(font
				(size 1.27 1.27)
			)
			(justify left bottom)
		)
	)
	(label "~{LED0_0}"
		(at 204.47 228.6 0)
		(effects
			(font
				(size 1.27 1.27)
			)
			(justify left bottom)
		)
	)
	(label "SFP0_LEDG"
		(at 241.3 231.14 180)
		(effects
			(font
				(size 1.27 1.27)
			)
			(justify right bottom)
		)
	)
	(label "SDA0"
		(at 255.27 68.58 0)
		(effects
			(font
				(size 1.27 1.27)
			)
			(justify left bottom)
		)
	)
	(label "SFP1_LEDG"
		(at 331.47 165.1 0)
		(effects
			(font
				(size 1.27 1.27)
			)
			(justify left bottom)
		)
	)
	(label "SCL1"
		(at 255.27 154.94 0)
		(effects
			(font
				(size 1.27 1.27)
			)
			(justify left bottom)
		)
	)
	(label "SFI0.RX+"
		(at 236.22 101.6 180)
		(effects
			(font
				(size 1.27 1.27)
			)
			(justify right bottom)
		)
	)
	(hierarchical_label "PHY1_{RESET}"
		(shape input)
		(at 142.24 189.23 180)
		(effects
			(font
				(size 1.27 1.27)
			)
			(justify right)
		)
	)
	(hierarchical_label "I2C_{SFP0}{I2C}"
		(shape input)
		(at 142.24 66.04 180)
		(effects
			(font
				(size 1.27 1.27)
			)
			(justify right)
		)
	)
	(hierarchical_label "I2C_{LED}{I2C}"
		(shape input)
		(at 142.24 229.87 180)
		(effects
			(font
				(size 1.27 1.27)
			)
			(justify right)
		)
	)
	(hierarchical_label "10GKR_SFP0{10GBaseKR}"
		(shape input)
		(at 142.24 88.9 180)
		(effects
			(font
				(size 1.27 1.27)
			)
			(justify right)
		)
	)
	(hierarchical_label "MOD1_ABS"
		(shape output)
		(at 142.24 160.02 180)
		(effects
			(font
				(size 1.27 1.27)
			)
			(justify right)
		)
	)
	(hierarchical_label "PHY0_{RESET}"
		(shape input)
		(at 142.24 105.41 180)
		(effects
			(font
				(size 1.27 1.27)
			)
			(justify right)
		)
	)
	(hierarchical_label "MOD0_ABS"
		(shape output)
		(at 142.24 76.2 180)
		(effects
			(font
				(size 1.27 1.27)
			)
			(justify right)
		)
	)
	(hierarchical_label "~{RESET}"
		(shape input)
		(at 142.24 251.46 180)
		(effects
			(font
				(size 1.27 1.27)
			)
			(justify right)
		)
	)
	(hierarchical_label "10GKR_SFP1{10GBaseKR}"
		(shape input)
		(at 142.24 172.72 180)
		(effects
			(font
				(size 1.27 1.27)
			)
			(justify right)
		)
	)
	(hierarchical_label "MDIO1{MDIO}"
		(shape input)
		(at 142.24 186.69 180)
		(effects
			(font
				(size 1.27 1.27)
			)
			(justify right)
		)
	)
	(hierarchical_label "I2C_{SFP1}{I2C}"
		(shape input)
		(at 142.24 149.86 180)
		(effects
			(font
				(size 1.27 1.27)
			)
			(justify right)
		)
	)
	(hierarchical_label "MDIO0{MDIO}"
		(shape input)
		(at 142.24 102.87 180)
		(effects
			(font
				(size 1.27 1.27)
			)
			(justify right)
		)
	)
	(symbol
		(lib_id "antmicroInterfaceIOExpanders:PCA9539AHF")
		(at 180.34 228.6 0)
		(unit 1)
		(exclude_from_sim no)
		(in_bom yes)
		(on_board yes)
		(dnp no)
		(fields_autoplaced yes)
		(property "Reference" "U5"
			(at 191.77 220.98 0)
			(effects
				(font
					(size 1.27 1.27)
					(thickness 0.15)
				)
			)
		)
		(property "Value" "PCA9539AHF"
			(at 213.36 238.76 0)
			(effects
				(font
					(size 1.27 1.27)
					(thickness 0.15)
				)
				(justify left bottom)
				(hide yes)
			)
		)
		(property "Footprint" "antmicro-footprints:QFN-24-1EP_4x4mm_P0.5_EP2.1x2.1mm"
			(at 213.36 241.3 0)
			(effects
				(font
					(size 1.27 1.27)
					(thickness 0.15)
				)
				(justify left bottom)
				(hide yes)
			)
		)
		(property "Datasheet" "https://www.nxp.com/docs/en/data-sheet/PCA9539A.pdf"
			(at 213.36 243.84 0)
			(effects
				(font
					(size 1.27 1.27)
					(thickness 0.15)
				)
				(justify left bottom)
				(hide yes)
			)
		)
		(property "Description" ""
			(at 180.34 228.6 0)
			(effects
				(font
					(size 1.27 1.27)
				)
				(hide yes)
			)
		)
		(property "MPN" "PCA9539AHF,128"
			(at 191.77 223.52 0)
			(effects
				(font
					(size 1.27 1.27)
					(thickness 0.15)
				)
			)
		)
		(property "Manufacturer" "NXP"
			(at 213.36 246.38 0)
			(effects
				(font
					(size 1.27 1.27)
					(thickness 0.15)
				)
				(justify left bottom)
				(hide yes)
			)
		)
		(property "Author" "Antmicro"
			(at 213.36 248.92 0)
			(effects
				(font
					(size 1.27 1.27)
					(thickness 0.15)
				)
				(justify left bottom)
				(hide yes)
			)
		)
		(property "License" "Apache-2.0"
			(at 213.36 251.46 0)
			(effects
				(font
					(size 1.27 1.27)
					(thickness 0.15)
				)
				(justify left bottom)
				(hide yes)
			)
		)
		(pin "17"
		)
		(pin "18"
		)
		(pin "4"
		)
		(pin "3"
		)
		(pin "9"
		)
		(pin "5"
		)
		(pin "6"
		)
		(pin "15"
		)
		(pin "20"
		)
		(pin "2"
		)
		(pin "13"
		)
		(pin "12"
		)
		(pin "24"
		)
		(pin "8"
		)
		(pin "25"
		)
		(pin "22"
		)
		(pin "23"
		)
		(pin "11"
		)
		(pin "10"
		)
		(pin "14"
		)
		(pin "1"
		)
		(pin "7"
		)
		(pin "21"
		)
		(pin "16"
		)
		(pin "19"
		)
		(instances
			(project "com-express-7-baseboard"
				(path ""
					(reference "U5")
					(unit 1)
				)
			)
		)
	)
	(symbol
		(lib_id "antmicropower:GND")
		(at 303.53 114.3 0)
		(mirror y)
		(unit 1)
		(exclude_from_sim no)
		(in_bom yes)
		(on_board yes)
		(dnp no)
		(property "Reference" "#PWR052"
			(at 294.64 116.84 0)
			(effects
				(font
					(size 1.27 1.27)
					(thickness 0.15)
				)
				(justify left bottom)
				(hide yes)
			)
		)
		(property "Value" "GND"
			(at 303.53 118.11 0)
			(effects
				(font
					(size 1.27 1.27)
					(thickness 0.15)
				)
			)
		)
		(property "Footprint" ""
			(at 294.64 121.92 0)
			(effects
				(font
					(size 1.27 1.27)
					(thickness 0.15)
				)
				(justify left bottom)
				(hide yes)
			)
		)
		(property "Datasheet" ""
			(at 294.64 127 0)
			(effects
				(font
					(size 1.27 1.27)
					(thickness 0.15)
				)
				(justify left bottom)
				(hide yes)
			)
		)
		(property "Description" ""
			(at 303.53 114.3 0)
			(effects
				(font
					(size 1.27 1.27)
				)
				(hide yes)
			)
		)
		(property "Author" "Antmicro"
			(at 294.64 121.92 0)
			(effects
				(font
					(size 1.27 1.27)
					(thickness 0.15)
				)
				(justify left bottom)
				(hide yes)
			)
		)
		(property "License" "Apache-2.0"
			(at 294.64 124.46 0)
			(effects
				(font
					(size 1.27 1.27)
					(thickness 0.15)
				)
				(justify left bottom)
				(hide yes)
			)
		)
		(pin "1"
		)
		(instances
			(project "com-express-7-baseboard"
				(path ""
					(reference "#PWR052")
					(unit 1)
				)
			)
		)
	)
	(symbol
		(lib_id "antmicroResistors0402:R_0R_0402")
		(at 219.71 231.14 0)
		(unit 1)
		(exclude_from_sim no)
		(in_bom yes)
		(on_board yes)
		(dnp no)
		(property "Reference" "R44"
			(at 217.17 229.87 0)
			(effects
				(font
					(size 1.27 1.27)
					(thickness 0.15)
				)
			)
		)
		(property "Value" "R_0R_0402"
			(at 240.03 243.84 0)
			(effects
				(font
					(size 1.27 1.27)
					(thickness 0.15)
				)
				(justify left bottom)
				(hide yes)
			)
		)
		(property "Footprint" "antmicro-footprints:R_0402_1005Metric"
			(at 240.03 246.38 0)
			(effects
				(font
					(size 1.27 1.27)
					(thickness 0.15)
				)
				(justify left bottom)
				(hide yes)
			)
		)
		(property "Datasheet" "https://industrial.panasonic.com/cdbs/www-data/pdf/RDA0000/AOA0000C301.pdf"
			(at 240.03 248.92 0)
			(effects
				(font
					(size 1.27 1.27)
					(thickness 0.15)
				)
				(justify left bottom)
				(hide yes)
			)
		)
		(property "Description" ""
			(at 219.71 231.14 0)
			(effects
				(font
					(size 1.27 1.27)
				)
				(hide yes)
			)
		)
		(property "MPN" "ERJ2GE0R00X"
			(at 240.03 251.46 0)
			(effects
				(font
					(size 1.27 1.27)
					(thickness 0.15)
				)
				(justify left bottom)
				(hide yes)
			)
		)
		(property "Manufacturer" "Panasonic"
			(at 240.03 254 0)
			(effects
				(font
					(size 1.27 1.27)
					(thickness 0.15)
				)
				(justify left bottom)
				(hide yes)
			)
		)
		(property "License" "Apache-2.0"
			(at 240.03 256.54 0)
			(effects
				(font
					(size 1.27 1.27)
					(thickness 0.15)
				)
				(justify left bottom)
				(hide yes)
			)
		)
		(property "Author" "Antmicro"
			(at 240.03 259.08 0)
			(effects
				(font
					(size 1.27 1.27)
					(thickness 0.15)
				)
				(justify left bottom)
				(hide yes)
			)
		)
		(property "Val" "0R"
			(at 226.06 229.87 0)
			(effects
				(font
					(size 1.27 1.27)
					(thickness 0.15)
				)
			)
		)
		(property "Tolerance" "~"
			(at 240.03 241.3 0)
			(effects
				(font
					(size 1.27 1.27)
				)
				(justify left bottom)
				(hide yes)
			)
		)
		(property "Current" "1A"
			(at 240.03 261.62 0)
			(effects
				(font
					(size 1.27 1.27)
					(thickness 0.15)
				)
				(justify left bottom)
				(hide yes)
			)
		)
		(property "Public" "False"
			(at 240.03 261.62 0)
			(effects
				(font
					(size 1.27 1.27)
				)
				(justify left bottom)
				(hide yes)
			)
		)
		(pin "2"
		)
		(pin "1"
		)
		(instances
			(project "com-express-7-baseboard"
				(path ""
					(reference "R44")
					(unit 1)
				)
			)
		)
	)
	(symbol
		(lib_id "antmicroResistors0402:R_1k_0402")
		(at 250.19 147.32 90)
		(unit 1)
		(exclude_from_sim no)
		(in_bom yes)
		(on_board yes)
		(dnp no)
		(property "Reference" "R56"
			(at 251.46 143.51 90)
			(effects
				(font
					(size 1.27 1.27)
					(thickness 0.15)
				)
				(justify right)
			)
		)
		(property "Value" "R_1k_0402"
			(at 262.89 127 0)
			(effects
				(font
					(size 1.27 1.27)
					(thickness 0.15)
				)
				(justify left bottom)
				(hide yes)
			)
		)
		(property "Footprint" "antmicro-footprints:R_0402_1005Metric"
			(at 265.43 127 0)
			(effects
				(font
					(size 1.27 1.27)
					(thickness 0.15)
				)
				(justify left bottom)
				(hide yes)
			)
		)
		(property "Datasheet" "https://www.bourns.com/docs/product-datasheets/cr.pdf"
			(at 267.97 127 0)
			(effects
				(font
					(size 1.27 1.27)
					(thickness 0.15)
				)
				(justify left bottom)
				(hide yes)
			)
		)
		(property "Description" ""
			(at 250.19 147.32 0)
			(effects
				(font
					(size 1.27 1.27)
				)
				(hide yes)
			)
		)
		(property "MPN" "CR0402-FX-1001GLF"
			(at 270.51 127 0)
			(effects
				(font
					(size 1.27 1.27)
					(thickness 0.15)
				)
				(justify left bottom)
				(hide yes)
			)
		)
		(property "Manufacturer" "Bourns"
			(at 273.05 127 0)
			(effects
				(font
					(size 1.27 1.27)
					(thickness 0.15)
				)
				(justify left bottom)
				(hide yes)
			)
		)
		(property "License" "Apache-2.0"
			(at 275.59 127 0)
			(effects
				(font
					(size 1.27 1.27)
					(thickness 0.15)
				)
				(justify left bottom)
				(hide yes)
			)
		)
		(property "Author" "Antmicro"
			(at 278.13 127 0)
			(effects
				(font
					(size 1.27 1.27)
					(thickness 0.15)
				)
				(justify left bottom)
				(hide yes)
			)
		)
		(property "Val" "1k"
			(at 251.46 146.05 90)
			(effects
				(font
					(size 1.27 1.27)
					(thickness 0.15)
				)
				(justify right)
			)
		)
		(property "Tolerance" "1%"
			(at 260.35 127 0)
			(effects
				(font
					(size 1.27 1.27)
				)
				(justify left bottom)
				(hide yes)
			)
		)
		(property "Public" "False"
			(at 280.67 127 0)
			(effects
				(font
					(size 1.27 1.27)
				)
				(justify left bottom)
				(hide yes)
			)
		)
		(pin "2"
		)
		(pin "1"
		)
		(instances
			(project "com-express-7-baseboard"
				(path ""
					(reference "R56")
					(unit 1)
				)
			)
		)
	)
	(symbol
		(lib_id "antmicroCapacitors0402:C_100n_0402")
		(at 347.98 104.14 90)
		(mirror x)
		(unit 1)
		(exclude_from_sim no)
		(in_bom yes)
		(on_board yes)
		(dnp no)
		(property "Reference" "C212"
			(at 354.33 105.41 90)
			(effects
				(font
					(size 1.27 1.27)
					(thickness 0.15)
				)
				(justify left)
			)
		)
		(property "Value" "C_100n_0402"
			(at 358.14 124.46 0)
			(effects
				(font
					(size 1.27 1.27)
					(thickness 0.15)
				)
				(justify left bottom)
				(hide yes)
			)
		)
		(property "Footprint" "antmicro-footprints:C_0402_1005Metric"
			(at 360.68 124.46 0)
			(effects
				(font
					(size 1.27 1.27)
					(thickness 0.15)
				)
				(justify left bottom)
				(hide yes)
			)
		)
		(property "Datasheet" "https://www.murata.com/products/productdetail?partno=GRM155R61H104KE14%23"
			(at 363.22 124.46 0)
			(effects
				(font
					(size 1.27 1.27)
					(thickness 0.15)
				)
				(justify left bottom)
				(hide yes)
			)
		)
		(property "Description" ""
			(at 347.98 104.14 0)
			(effects
				(font
					(size 1.27 1.27)
				)
				(hide yes)
			)
		)
		(property "MPN" "GRM155R61H104KE14D"
			(at 365.76 124.46 0)
			(effects
				(font
					(size 1.27 1.27)
					(thickness 0.15)
				)
				(justify left bottom)
				(hide yes)
			)
		)
		(property "Manufacturer" "Murata"
			(at 368.3 124.46 0)
			(effects
				(font
					(size 1.27 1.27)
					(thickness 0.15)
				)
				(justify left bottom)
				(hide yes)
			)
		)
		(property "License" "Apache-2.0"
			(at 370.84 124.46 0)
			(effects
				(font
					(size 1.27 1.27)
					(thickness 0.15)
				)
				(justify left bottom)
				(hide yes)
			)
		)
		(property "Author" "Antmicro"
			(at 373.38 124.46 0)
			(effects
				(font
					(size 1.27 1.27)
					(thickness 0.15)
				)
				(justify left bottom)
				(hide yes)
			)
		)
		(property "Val" "100n"
			(at 354.33 107.95 90)
			(effects
				(font
					(size 1.27 1.27)
					(thickness 0.15)
				)
				(justify left)
			)
		)
		(property "Voltage" "50V"
			(at 375.92 124.46 0)
			(effects
				(font
					(size 1.27 1.27)
				)
				(justify left bottom)
				(hide yes)
			)
		)
		(property "Dielectric" "X5R"
			(at 378.46 124.46 0)
			(effects
				(font
					(size 1.27 1.27)
				)
				(justify left bottom)
				(hide yes)
			)
		)
		(property "Public" "False"
			(at 381 124.46 0)
			(effects
				(font
					(size 1.27 1.27)
				)
				(justify left bottom)
				(hide yes)
			)
		)
		(pin "1"
		)
		(pin "2"
		)
		(instances
			(project "com-express-7-baseboard"
				(path ""
					(reference "C212")
					(unit 1)
				)
			)
		)
	)
	(symbol
		(lib_id "antmicropower:GND")
		(at 168.91 224.79 0)
		(unit 1)
		(exclude_from_sim no)
		(in_bom yes)
		(on_board yes)
		(dnp no)
		(property "Reference" "#PWR037"
			(at 177.8 227.33 0)
			(effects
				(font
					(size 1.27 1.27)
					(thickness 0.15)
				)
				(justify left bottom)
				(hide yes)
			)
		)
		(property "Value" "GND"
			(at 168.91 228.6 0)
			(effects
				(font
					(size 1.27 1.27)
					(thickness 0.15)
				)
			)
		)
		(property "Footprint" ""
			(at 177.8 232.41 0)
			(effects
				(font
					(size 1.27 1.27)
					(thickness 0.15)
				)
				(justify left bottom)
				(hide yes)
			)
		)
		(property "Datasheet" ""
			(at 177.8 237.49 0)
			(effects
				(font
					(size 1.27 1.27)
					(thickness 0.15)
				)
				(justify left bottom)
				(hide yes)
			)
		)
		(property "Description" ""
			(at 168.91 224.79 0)
			(effects
				(font
					(size 1.27 1.27)
				)
				(hide yes)
			)
		)
		(property "Author" "Antmicro"
			(at 177.8 232.41 0)
			(effects
				(font
					(size 1.27 1.27)
					(thickness 0.15)
				)
				(justify left bottom)
				(hide yes)
			)
		)
		(property "License" "Apache-2.0"
			(at 177.8 234.95 0)
			(effects
				(font
					(size 1.27 1.27)
					(thickness 0.15)
				)
				(justify left bottom)
				(hide yes)
			)
		)
		(pin "1"
		)
		(instances
			(project "com-express-7-baseboard"
				(path ""
					(reference "#PWR037")
					(unit 1)
				)
			)
		)
	)
	(symbol
		(lib_id "antmicroTestPoints:TP_0.75mm_SMD")
		(at 203.2 243.84 0)
		(unit 1)
		(exclude_from_sim no)
		(in_bom no)
		(on_board yes)
		(dnp no)
		(property "Reference" "TP1"
			(at 207.01 243.84 0)
			(effects
				(font
					(size 1.27 1.27)
					(thickness 0.15)
				)
				(justify left)
			)
		)
		(property "Value" "TP_0.75mm_SMD"
			(at 213.995 247.65 0)
			(effects
				(font
					(size 1.27 1.27)
					(thickness 0.15)
				)
				(justify left bottom)
				(hide yes)
			)
		)
		(property "Footprint" "antmicro-footprints:TP_SMD_0.75mm"
			(at 213.995 250.19 0)
			(effects
				(font
					(size 1.27 1.27)
					(thickness 0.15)
				)
				(justify left bottom)
				(hide yes)
			)
		)
		(property "Datasheet" ""
			(at 220.98 256.54 0)
			(effects
				(font
					(size 1.27 1.27)
					(thickness 0.15)
				)
				(justify left bottom)
				(hide yes)
			)
		)
		(property "Description" ""
			(at 203.2 243.84 0)
			(effects
				(font
					(size 1.27 1.27)
				)
				(hide yes)
			)
		)
		(property "MPN" ""
			(at 213.995 255.27 0)
			(effects
				(font
					(size 1.27 1.27)
					(thickness 0.15)
				)
				(justify left bottom)
				(hide yes)
			)
		)
		(property "Manufacturer" ""
			(at 213.995 250.19 0)
			(effects
				(font
					(size 1.27 1.27)
					(thickness 0.15)
				)
				(justify left bottom)
				(hide yes)
			)
		)
		(property "Author" "Antmicro"
			(at 213.995 252.73 0)
			(effects
				(font
					(size 1.27 1.27)
					(thickness 0.15)
				)
				(justify left bottom)
				(hide yes)
			)
		)
		(property "License" "Apache-2.0"
			(at 213.995 255.27 0)
			(effects
				(font
					(size 1.27 1.27)
					(thickness 0.15)
				)
				(justify left bottom)
				(hide yes)
			)
		)
		(property "Public" "False"
			(at 213.36 257.81 0)
			(effects
				(font
					(size 1.27 1.27)
				)
				(justify left bottom)
				(hide yes)
			)
		)
		(pin "1"
		)
		(instances
			(project "com-express-7-baseboard"
				(path ""
					(reference "TP1")
					(unit 1)
				)
			)
		)
	)
	(symbol
		(lib_id "antmicropower:GND")
		(at 290.83 189.23 0)
		(unit 1)
		(exclude_from_sim no)
		(in_bom yes)
		(on_board yes)
		(dnp no)
		(property "Reference" "#PWR051"
			(at 299.72 191.77 0)
			(effects
				(font
					(size 1.27 1.27)
					(thickness 0.15)
				)
				(justify left bottom)
				(hide yes)
			)
		)
		(property "Value" "GND"
			(at 290.83 193.04 0)
			(effects
				(font
					(size 1.27 1.27)
					(thickness 0.15)
				)
			)
		)
		(property "Footprint" ""
			(at 299.72 196.85 0)
			(effects
				(font
					(size 1.27 1.27)
					(thickness 0.15)
				)
				(justify left bottom)
				(hide yes)
			)
		)
		(property "Datasheet" ""
			(at 299.72 201.93 0)
			(effects
				(font
					(size 1.27 1.27)
					(thickness 0.15)
				)
				(justify left bottom)
				(hide yes)
			)
		)
		(property "Description" ""
			(at 290.83 189.23 0)
			(effects
				(font
					(size 1.27 1.27)
				)
				(hide yes)
			)
		)
		(property "Author" "Antmicro"
			(at 299.72 196.85 0)
			(effects
				(font
					(size 1.27 1.27)
					(thickness 0.15)
				)
				(justify left bottom)
				(hide yes)
			)
		)
		(property "License" "Apache-2.0"
			(at 299.72 199.39 0)
			(effects
				(font
					(size 1.27 1.27)
					(thickness 0.15)
				)
				(justify left bottom)
				(hide yes)
			)
		)
		(pin "1"
		)
		(instances
			(project "com-express-7-baseboard"
				(path ""
					(reference "#PWR051")
					(unit 1)
				)
			)
		)
	)
	(symbol
		(lib_id "antmicropower:GND")
		(at 356.87 114.3 0)
		(mirror y)
		(unit 1)
		(exclude_from_sim no)
		(in_bom yes)
		(on_board yes)
		(dnp no)
		(property "Reference" "#PWR0456"
			(at 347.98 116.84 0)
			(effects
				(font
					(size 1.27 1.27)
					(thickness 0.15)
				)
				(justify left bottom)
				(hide yes)
			)
		)
		(property "Value" "GND"
			(at 356.87 118.11 0)
			(effects
				(font
					(size 1.27 1.27)
					(thickness 0.15)
				)
			)
		)
		(property "Footprint" ""
			(at 347.98 121.92 0)
			(effects
				(font
					(size 1.27 1.27)
					(thickness 0.15)
				)
				(justify left bottom)
				(hide yes)
			)
		)
		(property "Datasheet" ""
			(at 347.98 127 0)
			(effects
				(font
					(size 1.27 1.27)
					(thickness 0.15)
				)
				(justify left bottom)
				(hide yes)
			)
		)
		(property "Description" ""
			(at 356.87 114.3 0)
			(effects
				(font
					(size 1.27 1.27)
				)
				(hide yes)
			)
		)
		(property "Author" "Antmicro"
			(at 347.98 121.92 0)
			(effects
				(font
					(size 1.27 1.27)
					(thickness 0.15)
				)
				(justify left bottom)
				(hide yes)
			)
		)
		(property "License" "Apache-2.0"
			(at 347.98 124.46 0)
			(effects
				(font
					(size 1.27 1.27)
					(thickness 0.15)
				)
				(justify left bottom)
				(hide yes)
			)
		)
		(pin "1"
		)
		(instances
			(project "com-express-7-baseboard"
				(path ""
					(reference "#PWR0456")
					(unit 1)
				)
			)
		)
	)
	(symbol
		(lib_id "antmicropower:GND")
		(at 241.3 43.18 0)
		(mirror y)
		(unit 1)
		(exclude_from_sim no)
		(in_bom yes)
		(on_board yes)
		(dnp no)
		(property "Reference" "#PWR044"
			(at 232.41 45.72 0)
			(effects
				(font
					(size 1.27 1.27)
					(thickness 0.15)
				)
				(justify left bottom)
				(hide yes)
			)
		)
		(property "Value" "GND"
			(at 241.3 46.99 0)
			(effects
				(font
					(size 1.27 1.27)
					(thickness 0.15)
				)
			)
		)
		(property "Footprint" ""
			(at 232.41 50.8 0)
			(effects
				(font
					(size 1.27 1.27)
					(thickness 0.15)
				)
				(justify left bottom)
				(hide yes)
			)
		)
		(property "Datasheet" ""
			(at 232.41 55.88 0)
			(effects
				(font
					(size 1.27 1.27)
					(thickness 0.15)
				)
				(justify left bottom)
				(hide yes)
			)
		)
		(property "Description" ""
			(at 241.3 43.18 0)
			(effects
				(font
					(size 1.27 1.27)
				)
				(hide yes)
			)
		)
		(property "Author" "Antmicro"
			(at 232.41 50.8 0)
			(effects
				(font
					(size 1.27 1.27)
					(thickness 0.15)
				)
				(justify left bottom)
				(hide yes)
			)
		)
		(property "License" "Apache-2.0"
			(at 232.41 53.34 0)
			(effects
				(font
					(size 1.27 1.27)
					(thickness 0.15)
				)
				(justify left bottom)
				(hide yes)
			)
		)
		(pin "1"
		)
		(instances
			(project "com-express-7-baseboard"
				(path ""
					(reference "#PWR044")
					(unit 1)
				)
			)
		)
	)
	(symbol
		(lib_id "antmicroResistors0402:R_0R_0402")
		(at 194.31 71.12 0)
		(unit 1)
		(exclude_from_sim no)
		(in_bom yes)
		(on_board yes)
		(dnp no)
		(property "Reference" "R38"
			(at 191.77 69.85 0)
			(effects
				(font
					(size 1.27 1.27)
					(thickness 0.15)
				)
			)
		)
		(property "Value" "R_0R_0402"
			(at 214.63 83.82 0)
			(effects
				(font
					(size 1.27 1.27)
					(thickness 0.15)
				)
				(justify left bottom)
				(hide yes)
			)
		)
		(property "Footprint" "antmicro-footprints:R_0402_1005Metric"
			(at 214.63 86.36 0)
			(effects
				(font
					(size 1.27 1.27)
					(thickness 0.15)
				)
				(justify left bottom)
				(hide yes)
			)
		)
		(property "Datasheet" "https://industrial.panasonic.com/cdbs/www-data/pdf/RDA0000/AOA0000C301.pdf"
			(at 214.63 88.9 0)
			(effects
				(font
					(size 1.27 1.27)
					(thickness 0.15)
				)
				(justify left bottom)
				(hide yes)
			)
		)
		(property "Description" ""
			(at 194.31 71.12 0)
			(effects
				(font
					(size 1.27 1.27)
				)
				(hide yes)
			)
		)
		(property "MPN" "ERJ2GE0R00X"
			(at 214.63 91.44 0)
			(effects
				(font
					(size 1.27 1.27)
					(thickness 0.15)
				)
				(justify left bottom)
				(hide yes)
			)
		)
		(property "Manufacturer" "Panasonic"
			(at 214.63 93.98 0)
			(effects
				(font
					(size 1.27 1.27)
					(thickness 0.15)
				)
				(justify left bottom)
				(hide yes)
			)
		)
		(property "License" "Apache-2.0"
			(at 214.63 96.52 0)
			(effects
				(font
					(size 1.27 1.27)
					(thickness 0.15)
				)
				(justify left bottom)
				(hide yes)
			)
		)
		(property "Author" "Antmicro"
			(at 214.63 99.06 0)
			(effects
				(font
					(size 1.27 1.27)
					(thickness 0.15)
				)
				(justify left bottom)
				(hide yes)
			)
		)
		(property "Val" "0R"
			(at 200.66 69.85 0)
			(effects
				(font
					(size 1.27 1.27)
					(thickness 0.15)
				)
			)
		)
		(property "Tolerance" "~"
			(at 214.63 81.28 0)
			(effects
				(font
					(size 1.27 1.27)
				)
				(justify left bottom)
				(hide yes)
			)
		)
		(property "Current" "1A"
			(at 214.63 101.6 0)
			(effects
				(font
					(size 1.27 1.27)
					(thickness 0.15)
				)
				(justify left bottom)
				(hide yes)
			)
		)
		(property "Public" "False"
			(at 214.63 101.6 0)
			(effects
				(font
					(size 1.27 1.27)
				)
				(justify left bottom)
				(hide yes)
			)
		)
		(pin "2"
		)
		(pin "1"
		)
		(instances
			(project "com-express-7-baseboard"
				(path ""
					(reference "R38")
					(unit 1)
				)
			)
		)
	)
	(symbol
		(lib_id "antmicropower:GND")
		(at 243.84 168.91 0)
		(unit 1)
		(exclude_from_sim no)
		(in_bom yes)
		(on_board yes)
		(dnp no)
		(property "Reference" "#PWR047"
			(at 252.73 171.45 0)
			(effects
				(font
					(size 1.27 1.27)
					(thickness 0.15)
				)
				(justify left bottom)
				(hide yes)
			)
		)
		(property "Value" "GND"
			(at 240.03 170.18 0)
			(effects
				(font
					(size 1.27 1.27)
					(thickness 0.15)
				)
			)
		)
		(property "Footprint" ""
			(at 252.73 176.53 0)
			(effects
				(font
					(size 1.27 1.27)
					(thickness 0.15)
				)
				(justify left bottom)
				(hide yes)
			)
		)
		(property "Datasheet" ""
			(at 252.73 181.61 0)
			(effects
				(font
					(size 1.27 1.27)
					(thickness 0.15)
				)
				(justify left bottom)
				(hide yes)
			)
		)
		(property "Description" ""
			(at 243.84 168.91 0)
			(effects
				(font
					(size 1.27 1.27)
				)
				(hide yes)
			)
		)
		(property "Author" "Antmicro"
			(at 252.73 176.53 0)
			(effects
				(font
					(size 1.27 1.27)
					(thickness 0.15)
				)
				(justify left bottom)
				(hide yes)
			)
		)
		(property "License" "Apache-2.0"
			(at 252.73 179.07 0)
			(effects
				(font
					(size 1.27 1.27)
					(thickness 0.15)
				)
				(justify left bottom)
				(hide yes)
			)
		)
		(pin "1"
		)
		(instances
			(project "com-express-7-baseboard"
				(path ""
					(reference "#PWR047")
					(unit 1)
				)
			)
		)
	)
	(symbol
		(lib_id "antmicroTestPoints:TP_0.75mm_SMD")
		(at 241.3 78.74 180)
		(unit 1)
		(exclude_from_sim no)
		(in_bom no)
		(on_board yes)
		(dnp no)
		(property "Reference" "TP5"
			(at 232.41 78.74 0)
			(effects
				(font
					(size 1.27 1.27)
					(thickness 0.15)
				)
			)
		)
		(property "Value" "TP_0.75mm_SMD"
			(at 230.505 74.93 0)
			(effects
				(font
					(size 1.27 1.27)
					(thickness 0.15)
				)
				(justify left bottom)
				(hide yes)
			)
		)
		(property "Footprint" "antmicro-footprints:TP_SMD_0.75mm"
			(at 230.505 72.39 0)
			(effects
				(font
					(size 1.27 1.27)
					(thickness 0.15)
				)
				(justify left bottom)
				(hide yes)
			)
		)
		(property "Datasheet" ""
			(at 223.52 66.04 0)
			(effects
				(font
					(size 1.27 1.27)
					(thickness 0.15)
				)
				(justify left bottom)
				(hide yes)
			)
		)
		(property "Description" ""
			(at 241.3 78.74 0)
			(effects
				(font
					(size 1.27 1.27)
				)
				(hide yes)
			)
		)
		(property "MPN" ""
			(at 230.505 67.31 0)
			(effects
				(font
					(size 1.27 1.27)
					(thickness 0.15)
				)
				(justify left bottom)
				(hide yes)
			)
		)
		(property "Manufacturer" ""
			(at 230.505 72.39 0)
			(effects
				(font
					(size 1.27 1.27)
					(thickness 0.15)
				)
				(justify left bottom)
				(hide yes)
			)
		)
		(property "Author" "Antmicro"
			(at 230.505 69.85 0)
			(effects
				(font
					(size 1.27 1.27)
					(thickness 0.15)
				)
				(justify left bottom)
				(hide yes)
			)
		)
		(property "License" "Apache-2.0"
			(at 230.505 67.31 0)
			(effects
				(font
					(size 1.27 1.27)
					(thickness 0.15)
				)
				(justify left bottom)
				(hide yes)
			)
		)
		(property "Public" "False"
			(at 231.14 64.77 0)
			(effects
				(font
					(size 1.27 1.27)
				)
				(justify left bottom)
				(hide yes)
			)
		)
		(pin "1"
		)
		(instances
			(project "com-express-7-baseboard"
				(path ""
					(reference "TP5")
					(unit 1)
				)
			)
		)
	)
	(symbol
		(lib_id "antmicroLEDIndicationDiscrete:LED_Y_0603_LTST-C191KSKT")
		(at 322.58 76.2 90)
		(unit 1)
		(exclude_from_sim no)
		(in_bom yes)
		(on_board yes)
		(dnp no)
		(fields_autoplaced yes)
		(property "Reference" "D4"
			(at 325.12 72.39 90)
			(effects
				(font
					(size 1.27 1.27)
					(thickness 0.15)
				)
				(justify right)
			)
		)
		(property "Value" "LED_Y_0603_LTST-C191KSKT"
			(at 330.2 53.34 0)
			(effects
				(font
					(size 1.27 1.27)
					(thickness 0.15)
				)
				(justify left bottom)
				(hide yes)
			)
		)
		(property "Footprint" "antmicro-footprints:LED_0603_1608Metric_Y"
			(at 332.74 53.34 0)
			(effects
				(font
					(size 1.27 1.27)
					(thickness 0.15)
				)
				(justify left bottom)
				(hide yes)
			)
		)
		(property "Datasheet" "https://optoelectronics.liteon.com/upload/download/DS22-2000-224/LTST-C191KSKT.PDF"
			(at 335.28 53.34 0)
			(effects
				(font
					(size 1.27 1.27)
					(thickness 0.15)
				)
				(justify left bottom)
				(hide yes)
			)
		)
		(property "Description" ""
			(at 322.58 76.2 0)
			(effects
				(font
					(size 1.27 1.27)
				)
				(hide yes)
			)
		)
		(property "MPN" "LTST-C191KSKT"
			(at 337.82 53.34 0)
			(effects
				(font
					(size 1.27 1.27)
					(thickness 0.15)
				)
				(justify left bottom)
				(hide yes)
			)
		)
		(property "Manufacturer" "Lite-On"
			(at 340.36 53.34 0)
			(effects
				(font
					(size 1.27 1.27)
					(thickness 0.15)
				)
				(justify left bottom)
				(hide yes)
			)
		)
		(property "Color" "Yellow"
			(at 325.12 74.93 90)
			(effects
				(font
					(size 1.27 1.27)
				)
				(justify right)
			)
		)
		(property "Author" "Antmicro"
			(at 342.9 53.34 0)
			(effects
				(font
					(size 1.27 1.27)
					(thickness 0.15)
				)
				(justify left bottom)
				(hide yes)
			)
		)
		(property "License" "Apache-2.0"
			(at 345.44 53.34 0)
			(effects
				(font
					(size 1.27 1.27)
					(thickness 0.15)
				)
				(justify left bottom)
				(hide yes)
			)
		)
		(pin "1"
		)
		(pin "2"
		)
		(instances
			(project "com-express-7-baseboard"
				(path ""
					(reference "D4")
					(unit 1)
				)
			)
		)
	)
	(symbol
		(lib_id "antmicropower:GND")
		(at 339.09 114.3 0)
		(mirror y)
		(unit 1)
		(exclude_from_sim no)
		(in_bom yes)
		(on_board yes)
		(dnp no)
		(property "Reference" "#PWR0454"
			(at 330.2 116.84 0)
			(effects
				(font
					(size 1.27 1.27)
					(thickness 0.15)
				)
				(justify left bottom)
				(hide yes)
			)
		)
		(property "Value" "GND"
			(at 339.09 118.11 0)
			(effects
				(font
					(size 1.27 1.27)
					(thickness 0.15)
				)
			)
		)
		(property "Footprint" ""
			(at 330.2 121.92 0)
			(effects
				(font
					(size 1.27 1.27)
					(thickness 0.15)
				)
				(justify left bottom)
				(hide yes)
			)
		)
		(property "Datasheet" ""
			(at 330.2 127 0)
			(effects
				(font
					(size 1.27 1.27)
					(thickness 0.15)
				)
				(justify left bottom)
				(hide yes)
			)
		)
		(property "Description" ""
			(at 339.09 114.3 0)
			(effects
				(font
					(size 1.27 1.27)
				)
				(hide yes)
			)
		)
		(property "Author" "Antmicro"
			(at 330.2 121.92 0)
			(effects
				(font
					(size 1.27 1.27)
					(thickness 0.15)
				)
				(justify left bottom)
				(hide yes)
			)
		)
		(property "License" "Apache-2.0"
			(at 330.2 124.46 0)
			(effects
				(font
					(size 1.27 1.27)
					(thickness 0.15)
				)
				(justify left bottom)
				(hide yes)
			)
		)
		(pin "1"
		)
		(instances
			(project "com-express-7-baseboard"
				(path ""
					(reference "#PWR0454")
					(unit 1)
				)
			)
		)
	)
	(symbol
		(lib_id "antmicroCapacitors0402:C_100n_0402")
		(at 339.09 104.14 90)
		(mirror x)
		(unit 1)
		(exclude_from_sim no)
		(in_bom yes)
		(on_board yes)
		(dnp no)
		(property "Reference" "C211"
			(at 345.44 105.41 90)
			(effects
				(font
					(size 1.27 1.27)
					(thickness 0.15)
				)
				(justify left)
			)
		)
		(property "Value" "C_100n_0402"
			(at 349.25 124.46 0)
			(effects
				(font
					(size 1.27 1.27)
					(thickness 0.15)
				)
				(justify left bottom)
				(hide yes)
			)
		)
		(property "Footprint" "antmicro-footprints:C_0402_1005Metric"
			(at 351.79 124.46 0)
			(effects
				(font
					(size 1.27 1.27)
					(thickness 0.15)
				)
				(justify left bottom)
				(hide yes)
			)
		)
		(property "Datasheet" "https://www.murata.com/products/productdetail?partno=GRM155R61H104KE14%23"
			(at 354.33 124.46 0)
			(effects
				(font
					(size 1.27 1.27)
					(thickness 0.15)
				)
				(justify left bottom)
				(hide yes)
			)
		)
		(property "Description" ""
			(at 339.09 104.14 0)
			(effects
				(font
					(size 1.27 1.27)
				)
				(hide yes)
			)
		)
		(property "MPN" "GRM155R61H104KE14D"
			(at 356.87 124.46 0)
			(effects
				(font
					(size 1.27 1.27)
					(thickness 0.15)
				)
				(justify left bottom)
				(hide yes)
			)
		)
		(property "Manufacturer" "Murata"
			(at 359.41 124.46 0)
			(effects
				(font
					(size 1.27 1.27)
					(thickness 0.15)
				)
				(justify left bottom)
				(hide yes)
			)
		)
		(property "License" "Apache-2.0"
			(at 361.95 124.46 0)
			(effects
				(font
					(size 1.27 1.27)
					(thickness 0.15)
				)
				(justify left bottom)
				(hide yes)
			)
		)
		(property "Author" "Antmicro"
			(at 364.49 124.46 0)
			(effects
				(font
					(size 1.27 1.27)
					(thickness 0.15)
				)
				(justify left bottom)
				(hide yes)
			)
		)
		(property "Val" "100n"
			(at 345.44 107.95 90)
			(effects
				(font
					(size 1.27 1.27)
					(thickness 0.15)
				)
				(justify left)
			)
		)
		(property "Voltage" "50V"
			(at 367.03 124.46 0)
			(effects
				(font
					(size 1.27 1.27)
				)
				(justify left bottom)
				(hide yes)
			)
		)
		(property "Dielectric" "X5R"
			(at 369.57 124.46 0)
			(effects
				(font
					(size 1.27 1.27)
				)
				(justify left bottom)
				(hide yes)
			)
		)
		(property "Public" "False"
			(at 372.11 124.46 0)
			(effects
				(font
					(size 1.27 1.27)
				)
				(justify left bottom)
				(hide yes)
			)
		)
		(pin "1"
		)
		(pin "2"
		)
		(instances
			(project "com-express-7-baseboard"
				(path ""
					(reference "C211")
					(unit 1)
				)
			)
		)
	)
	(symbol
		(lib_id "antmicropower:+3V3")
		(at 342.9 147.32 0)
		(unit 1)
		(exclude_from_sim no)
		(in_bom yes)
		(on_board yes)
		(dnp no)
		(property "Reference" "#PWR055"
			(at 342.9 151.13 0)
			(effects
				(font
					(size 1.27 1.27)
				)
				(justify left bottom)
				(hide yes)
			)
		)
		(property "Value" "+3V3"
			(at 340.36 143.51 0)
			(effects
				(font
					(size 1.27 1.27)
				)
				(justify left)
			)
		)
		(property "Footprint" ""
			(at 342.9 147.32 0)
			(effects
				(font
					(size 1.27 1.27)
				)
				(justify left bottom)
				(hide yes)
			)
		)
		(property "Datasheet" ""
			(at 342.9 147.32 0)
			(effects
				(font
					(size 1.27 1.27)
				)
				(justify left bottom)
				(hide yes)
			)
		)
		(property "Description" ""
			(at 342.9 147.32 0)
			(effects
				(font
					(size 1.27 1.27)
				)
				(hide yes)
			)
		)
		(property "Author" "Antmicro"
			(at 358.14 149.86 0)
			(effects
				(font
					(size 1.27 1.27)
					(thickness 0.15)
				)
				(justify left bottom)
				(hide yes)
			)
		)
		(property "License" "Apache-2.0"
			(at 358.14 152.4 0)
			(effects
				(font
					(size 1.27 1.27)
					(thickness 0.15)
				)
				(justify left bottom)
				(hide yes)
			)
		)
		(pin "1"
		)
		(instances
			(project "com-express-7-baseboard"
				(path ""
					(reference "#PWR055")
					(unit 1)
				)
			)
		)
	)
	(symbol
		(lib_id "antmicropower:GND")
		(at 321.31 114.3 0)
		(mirror y)
		(unit 1)
		(exclude_from_sim no)
		(in_bom yes)
		(on_board yes)
		(dnp no)
		(property "Reference" "#PWR0452"
			(at 312.42 116.84 0)
			(effects
				(font
					(size 1.27 1.27)
					(thickness 0.15)
				)
				(justify left bottom)
				(hide yes)
			)
		)
		(property "Value" "GND"
			(at 321.31 118.11 0)
			(effects
				(font
					(size 1.27 1.27)
					(thickness 0.15)
				)
			)
		)
		(property "Footprint" ""
			(at 312.42 121.92 0)
			(effects
				(font
					(size 1.27 1.27)
					(thickness 0.15)
				)
				(justify left bottom)
				(hide yes)
			)
		)
		(property "Datasheet" ""
			(at 312.42 127 0)
			(effects
				(font
					(size 1.27 1.27)
					(thickness 0.15)
				)
				(justify left bottom)
				(hide yes)
			)
		)
		(property "Description" ""
			(at 321.31 114.3 0)
			(effects
				(font
					(size 1.27 1.27)
				)
				(hide yes)
			)
		)
		(property "Author" "Antmicro"
			(at 312.42 121.92 0)
			(effects
				(font
					(size 1.27 1.27)
					(thickness 0.15)
				)
				(justify left bottom)
				(hide yes)
			)
		)
		(property "License" "Apache-2.0"
			(at 312.42 124.46 0)
			(effects
				(font
					(size 1.27 1.27)
					(thickness 0.15)
				)
				(justify left bottom)
				(hide yes)
			)
		)
		(pin "1"
		)
		(instances
			(project "com-express-7-baseboard"
				(path ""
					(reference "#PWR0452")
					(unit 1)
				)
			)
		)
	)
	(symbol
		(lib_id "antmicroWire2BoardConnectors:Bel-Fuse_SFP+_2x20_SS-79100-010")
		(at 261.62 144.78 0)
		(unit 2)
		(exclude_from_sim no)
		(in_bom yes)
		(on_board yes)
		(dnp no)
		(fields_autoplaced yes)
		(property "Reference" "J2"
			(at 275.59 137.16 0)
			(effects
				(font
					(size 1.27 1.27)
					(thickness 0.15)
				)
			)
		)
		(property "Value" "Bel-Fuse_SFP+_2x20_SS-79100-010"
			(at 303.53 154.94 0)
			(effects
				(font
					(size 1.27 1.27)
					(thickness 0.15)
				)
				(justify left bottom)
				(hide yes)
			)
		)
		(property "Footprint" "antmicro-footprints:Conn_Bel-Fuse_SFP+_2x20_SS-79100-010"
			(at 303.53 157.48 0)
			(effects
				(font
					(size 1.27 1.27)
					(thickness 0.15)
				)
				(justify left bottom)
				(hide yes)
			)
		)
		(property "Datasheet" "https://www.belfuse.com/resources/datasheets/stewartconnector/ds-STW-SFP-cages.pdf"
			(at 303.53 160.02 0)
			(effects
				(font
					(size 1.27 1.27)
					(thickness 0.15)
				)
				(justify left bottom)
				(hide yes)
			)
		)
		(property "Description" ""
			(at 261.62 144.78 0)
			(effects
				(font
					(size 1.27 1.27)
				)
				(hide yes)
			)
		)
		(property "MPN" "SS-79100-010"
			(at 275.59 139.7 0)
			(effects
				(font
					(size 1.27 1.27)
					(thickness 0.15)
				)
			)
		)
		(property "Manufacturer" "Bel Fuse"
			(at 303.53 152.4 0)
			(effects
				(font
					(size 1.27 1.27)
					(thickness 0.15)
				)
				(justify left bottom)
				(hide yes)
			)
		)
		(property "Author" "Antmicro"
			(at 303.53 162.56 0)
			(effects
				(font
					(size 1.27 1.27)
					(thickness 0.15)
				)
				(justify left bottom)
				(hide yes)
			)
		)
		(property "License" "Apache-2.0"
			(at 303.53 165.1 0)
			(effects
				(font
					(size 1.27 1.27)
					(thickness 0.15)
				)
				(justify left bottom)
				(hide yes)
			)
		)
		(pin "T6"
		)
		(pin "T4"
		)
		(pin "T10"
		)
		(pin "L12"
		)
		(pin "L11"
		)
		(pin "T5"
		)
		(pin "L13"
		)
		(pin "L19"
		)
		(pin "L2"
		)
		(pin "L9"
		)
		(pin "T3"
		)
		(pin "T9"
		)
		(pin "L7"
		)
		(pin "T19"
		)
		(pin "L18"
		)
		(pin "L5"
		)
		(pin "L14"
		)
		(pin "L10"
		)
		(pin "L16"
		)
		(pin "L17"
		)
		(pin "L20"
		)
		(pin "T18"
		)
		(pin "T17"
		)
		(pin "T16"
		)
		(pin "L15"
		)
		(pin "L1"
		)
		(pin "L8"
		)
		(pin "T2"
		)
		(pin "T14"
		)
		(pin "L3"
		)
		(pin "L6"
		)
		(pin "T20"
		)
		(pin "T8"
		)
		(pin "T1"
		)
		(pin "SH"
		)
		(pin "L4"
		)
		(pin "T7"
		)
		(pin "T11"
		)
		(pin "T12"
		)
		(pin "T13"
		)
		(pin "T15"
		)
		(instances
			(project "com-express-7-baseboard"
				(path ""
					(reference "J2")
					(unit 2)
				)
			)
		)
	)
	(symbol
		(lib_id "antmicroResistors0402:R_0R_0402")
		(at 194.31 160.02 0)
		(unit 1)
		(exclude_from_sim no)
		(in_bom yes)
		(on_board yes)
		(dnp no)
		(property "Reference" "R42"
			(at 191.77 158.75 0)
			(effects
				(font
					(size 1.27 1.27)
					(thickness 0.15)
				)
			)
		)
		(property "Value" "R_0R_0402"
			(at 214.63 172.72 0)
			(effects
				(font
					(size 1.27 1.27)
					(thickness 0.15)
				)
				(justify left bottom)
				(hide yes)
			)
		)
		(property "Footprint" "antmicro-footprints:R_0402_1005Metric"
			(at 214.63 175.26 0)
			(effects
				(font
					(size 1.27 1.27)
					(thickness 0.15)
				)
				(justify left bottom)
				(hide yes)
			)
		)
		(property "Datasheet" "https://industrial.panasonic.com/cdbs/www-data/pdf/RDA0000/AOA0000C301.pdf"
			(at 214.63 177.8 0)
			(effects
				(font
					(size 1.27 1.27)
					(thickness 0.15)
				)
				(justify left bottom)
				(hide yes)
			)
		)
		(property "Description" ""
			(at 194.31 160.02 0)
			(effects
				(font
					(size 1.27 1.27)
				)
				(hide yes)
			)
		)
		(property "MPN" "ERJ2GE0R00X"
			(at 214.63 180.34 0)
			(effects
				(font
					(size 1.27 1.27)
					(thickness 0.15)
				)
				(justify left bottom)
				(hide yes)
			)
		)
		(property "Manufacturer" "Panasonic"
			(at 214.63 182.88 0)
			(effects
				(font
					(size 1.27 1.27)
					(thickness 0.15)
				)
				(justify left bottom)
				(hide yes)
			)
		)
		(property "License" "Apache-2.0"
			(at 214.63 185.42 0)
			(effects
				(font
					(size 1.27 1.27)
					(thickness 0.15)
				)
				(justify left bottom)
				(hide yes)
			)
		)
		(property "Author" "Antmicro"
			(at 214.63 187.96 0)
			(effects
				(font
					(size 1.27 1.27)
					(thickness 0.15)
				)
				(justify left bottom)
				(hide yes)
			)
		)
		(property "Val" "0R"
			(at 200.66 158.75 0)
			(effects
				(font
					(size 1.27 1.27)
					(thickness 0.15)
				)
			)
		)
		(property "Tolerance" "~"
			(at 214.63 170.18 0)
			(effects
				(font
					(size 1.27 1.27)
				)
				(justify left bottom)
				(hide yes)
			)
		)
		(property "Current" "1A"
			(at 214.63 190.5 0)
			(effects
				(font
					(size 1.27 1.27)
					(thickness 0.15)
				)
				(justify left bottom)
				(hide yes)
			)
		)
		(property "Public" "False"
			(at 214.63 190.5 0)
			(effects
				(font
					(size 1.27 1.27)
				)
				(justify left bottom)
				(hide yes)
			)
		)
		(pin "2"
		)
		(pin "1"
		)
		(instances
			(project "com-express-7-baseboard"
				(path ""
					(reference "R42")
					(unit 1)
				)
			)
		)
	)
	(symbol
		(lib_id "antmicropower:+3V3")
		(at 322.58 69.85 0)
		(unit 1)
		(exclude_from_sim no)
		(in_bom yes)
		(on_board yes)
		(dnp no)
		(property "Reference" "#PWR054"
			(at 322.58 73.66 0)
			(effects
				(font
					(size 1.27 1.27)
				)
				(justify left bottom)
				(hide yes)
			)
		)
		(property "Value" "+3V3"
			(at 320.04 66.04 0)
			(effects
				(font
					(size 1.27 1.27)
				)
				(justify left)
			)
		)
		(property "Footprint" ""
			(at 322.58 69.85 0)
			(effects
				(font
					(size 1.27 1.27)
				)
				(justify left bottom)
				(hide yes)
			)
		)
		(property "Datasheet" ""
			(at 322.58 69.85 0)
			(effects
				(font
					(size 1.27 1.27)
				)
				(justify left bottom)
				(hide yes)
			)
		)
		(property "Description" ""
			(at 322.58 69.85 0)
			(effects
				(font
					(size 1.27 1.27)
				)
				(hide yes)
			)
		)
		(property "Author" "Antmicro"
			(at 337.82 72.39 0)
			(effects
				(font
					(size 1.27 1.27)
					(thickness 0.15)
				)
				(justify left bottom)
				(hide yes)
			)
		)
		(property "License" "Apache-2.0"
			(at 337.82 74.93 0)
			(effects
				(font
					(size 1.27 1.27)
					(thickness 0.15)
				)
				(justify left bottom)
				(hide yes)
			)
		)
		(pin "1"
		)
		(instances
			(project "com-express-7-baseboard"
				(path ""
					(reference "#PWR054")
					(unit 1)
				)
			)
		)
	)
	(symbol
		(lib_id "antmicropower:GND")
		(at 250.19 43.18 0)
		(mirror y)
		(unit 1)
		(exclude_from_sim no)
		(in_bom yes)
		(on_board yes)
		(dnp no)
		(property "Reference" "#PWR048"
			(at 241.3 45.72 0)
			(effects
				(font
					(size 1.27 1.27)
					(thickness 0.15)
				)
				(justify left bottom)
				(hide yes)
			)
		)
		(property "Value" "GND"
			(at 250.19 46.99 0)
			(effects
				(font
					(size 1.27 1.27)
					(thickness 0.15)
				)
			)
		)
		(property "Footprint" ""
			(at 241.3 50.8 0)
			(effects
				(font
					(size 1.27 1.27)
					(thickness 0.15)
				)
				(justify left bottom)
				(hide yes)
			)
		)
		(property "Datasheet" ""
			(at 241.3 55.88 0)
			(effects
				(font
					(size 1.27 1.27)
					(thickness 0.15)
				)
				(justify left bottom)
				(hide yes)
			)
		)
		(property "Description" ""
			(at 250.19 43.18 0)
			(effects
				(font
					(size 1.27 1.27)
				)
				(hide yes)
			)
		)
		(property "Author" "Antmicro"
			(at 241.3 50.8 0)
			(effects
				(font
					(size 1.27 1.27)
					(thickness 0.15)
				)
				(justify left bottom)
				(hide yes)
			)
		)
		(property "License" "Apache-2.0"
			(at 241.3 53.34 0)
			(effects
				(font
					(size 1.27 1.27)
					(thickness 0.15)
				)
				(justify left bottom)
				(hide yes)
			)
		)
		(pin "1"
		)
		(instances
			(project "com-express-7-baseboard"
				(path ""
					(reference "#PWR048")
					(unit 1)
				)
			)
		)
	)
	(symbol
		(lib_id "antmicroLEDIndicationDiscrete:LED_Y_0603_LTST-C191KSKT")
		(at 321.31 153.67 90)
		(unit 1)
		(exclude_from_sim no)
		(in_bom yes)
		(on_board yes)
		(dnp no)
		(fields_autoplaced yes)
		(property "Reference" "D5"
			(at 323.85 149.86 90)
			(effects
				(font
					(size 1.27 1.27)
					(thickness 0.15)
				)
				(justify right)
			)
		)
		(property "Value" "LED_Y_0603_LTST-C191KSKT"
			(at 328.93 130.81 0)
			(effects
				(font
					(size 1.27 1.27)
					(thickness 0.15)
				)
				(justify left bottom)
				(hide yes)
			)
		)
		(property "Footprint" "antmicro-footprints:LED_0603_1608Metric_Y"
			(at 331.47 130.81 0)
			(effects
				(font
					(size 1.27 1.27)
					(thickness 0.15)
				)
				(justify left bottom)
				(hide yes)
			)
		)
		(property "Datasheet" "https://optoelectronics.liteon.com/upload/download/DS22-2000-224/LTST-C191KSKT.PDF"
			(at 334.01 130.81 0)
			(effects
				(font
					(size 1.27 1.27)
					(thickness 0.15)
				)
				(justify left bottom)
				(hide yes)
			)
		)
		(property "Description" ""
			(at 321.31 153.67 0)
			(effects
				(font
					(size 1.27 1.27)
				)
				(hide yes)
			)
		)
		(property "MPN" "LTST-C191KSKT"
			(at 336.55 130.81 0)
			(effects
				(font
					(size 1.27 1.27)
					(thickness 0.15)
				)
				(justify left bottom)
				(hide yes)
			)
		)
		(property "Manufacturer" "Lite-On"
			(at 339.09 130.81 0)
			(effects
				(font
					(size 1.27 1.27)
					(thickness 0.15)
				)
				(justify left bottom)
				(hide yes)
			)
		)
		(property "Color" "Yellow"
			(at 323.85 152.4 90)
			(effects
				(font
					(size 1.27 1.27)
				)
				(justify right)
			)
		)
		(property "Author" "Antmicro"
			(at 341.63 130.81 0)
			(effects
				(font
					(size 1.27 1.27)
					(thickness 0.15)
				)
				(justify left bottom)
				(hide yes)
			)
		)
		(property "License" "Apache-2.0"
			(at 344.17 130.81 0)
			(effects
				(font
					(size 1.27 1.27)
					(thickness 0.15)
				)
				(justify left bottom)
				(hide yes)
			)
		)
		(pin "1"
		)
		(pin "2"
		)
		(instances
			(project "com-express-7-baseboard"
				(path ""
					(reference "D5")
					(unit 1)
				)
			)
		)
	)
	(symbol
		(lib_id "antmicropower:+3V3")
		(at 232.41 118.11 0)
		(unit 1)
		(exclude_from_sim no)
		(in_bom yes)
		(on_board yes)
		(dnp no)
		(fields_autoplaced yes)
		(property "Reference" "#PWR042"
			(at 247.65 118.11 0)
			(effects
				(font
					(size 1.27 1.27)
					(thickness 0.15)
				)
				(justify left bottom)
				(hide yes)
			)
		)
		(property "Value" "+3V3"
			(at 232.41 113.03 0)
			(effects
				(font
					(size 1.27 1.27)
					(thickness 0.15)
				)
			)
		)
		(property "Footprint" ""
			(at 247.65 125.73 0)
			(effects
				(font
					(size 1.27 1.27)
					(thickness 0.15)
				)
				(justify left bottom)
				(hide yes)
			)
		)
		(property "Datasheet" ""
			(at 247.65 128.27 0)
			(effects
				(font
					(size 1.27 1.27)
					(thickness 0.15)
				)
				(justify left bottom)
				(hide yes)
			)
		)
		(property "Description" ""
			(at 232.41 118.11 0)
			(effects
				(font
					(size 1.27 1.27)
				)
				(hide yes)
			)
		)
		(property "Author" "Antmicro"
			(at 247.65 120.65 0)
			(effects
				(font
					(size 1.27 1.27)
					(thickness 0.15)
				)
				(justify left bottom)
				(hide yes)
			)
		)
		(property "License" "Apache-2.0"
			(at 247.65 123.19 0)
			(effects
				(font
					(size 1.27 1.27)
					(thickness 0.15)
				)
				(justify left bottom)
				(hide yes)
			)
		)
		(pin "1"
		)
		(instances
			(project "com-express-7-baseboard"
				(path ""
					(reference "#PWR042")
					(unit 1)
				)
			)
		)
	)
	(symbol
		(lib_id "antmicropower:GND")
		(at 177.8 274.32 0)
		(unit 1)
		(exclude_from_sim no)
		(in_bom yes)
		(on_board yes)
		(dnp no)
		(property "Reference" "#PWR039"
			(at 186.69 276.86 0)
			(effects
				(font
					(size 1.27 1.27)
					(thickness 0.15)
				)
				(justify left bottom)
				(hide yes)
			)
		)
		(property "Value" "GND"
			(at 177.8 278.13 0)
			(effects
				(font
					(size 1.27 1.27)
					(thickness 0.15)
				)
			)
		)
		(property "Footprint" ""
			(at 186.69 281.94 0)
			(effects
				(font
					(size 1.27 1.27)
					(thickness 0.15)
				)
				(justify left bottom)
				(hide yes)
			)
		)
		(property "Datasheet" ""
			(at 186.69 287.02 0)
			(effects
				(font
					(size 1.27 1.27)
					(thickness 0.15)
				)
				(justify left bottom)
				(hide yes)
			)
		)
		(property "Description" ""
			(at 177.8 274.32 0)
			(effects
				(font
					(size 1.27 1.27)
				)
				(hide yes)
			)
		)
		(property "Author" "Antmicro"
			(at 186.69 281.94 0)
			(effects
				(font
					(size 1.27 1.27)
					(thickness 0.15)
				)
				(justify left bottom)
				(hide yes)
			)
		)
		(property "License" "Apache-2.0"
			(at 186.69 284.48 0)
			(effects
				(font
					(size 1.27 1.27)
					(thickness 0.15)
				)
				(justify left bottom)
				(hide yes)
			)
		)
		(pin "1"
		)
		(instances
			(project "com-express-7-baseboard"
				(path ""
					(reference "#PWR039")
					(unit 1)
				)
			)
		)
	)
	(symbol
		(lib_id "antmicropower:GND")
		(at 160.02 274.32 0)
		(unit 1)
		(exclude_from_sim no)
		(in_bom yes)
		(on_board yes)
		(dnp no)
		(property "Reference" "#PWR036"
			(at 168.91 276.86 0)
			(effects
				(font
					(size 1.27 1.27)
					(thickness 0.15)
				)
				(justify left bottom)
				(hide yes)
			)
		)
		(property "Value" "GND"
			(at 160.02 278.13 0)
			(effects
				(font
					(size 1.27 1.27)
					(thickness 0.15)
				)
			)
		)
		(property "Footprint" ""
			(at 168.91 281.94 0)
			(effects
				(font
					(size 1.27 1.27)
					(thickness 0.15)
				)
				(justify left bottom)
				(hide yes)
			)
		)
		(property "Datasheet" ""
			(at 168.91 287.02 0)
			(effects
				(font
					(size 1.27 1.27)
					(thickness 0.15)
				)
				(justify left bottom)
				(hide yes)
			)
		)
		(property "Description" ""
			(at 160.02 274.32 0)
			(effects
				(font
					(size 1.27 1.27)
				)
				(hide yes)
			)
		)
		(property "Author" "Antmicro"
			(at 168.91 281.94 0)
			(effects
				(font
					(size 1.27 1.27)
					(thickness 0.15)
				)
				(justify left bottom)
				(hide yes)
			)
		)
		(property "License" "Apache-2.0"
			(at 168.91 284.48 0)
			(effects
				(font
					(size 1.27 1.27)
					(thickness 0.15)
				)
				(justify left bottom)
				(hide yes)
			)
		)
		(pin "1"
		)
		(instances
			(project "com-express-7-baseboard"
				(path ""
					(reference "#PWR036")
					(unit 1)
				)
			)
		)
	)
	(symbol
		(lib_id "antmicropower:+3V3")
		(at 160.02 217.17 0)
		(unit 1)
		(exclude_from_sim no)
		(in_bom yes)
		(on_board yes)
		(dnp no)
		(fields_autoplaced yes)
		(property "Reference" "#PWR035"
			(at 175.26 217.17 0)
			(effects
				(font
					(size 1.27 1.27)
					(thickness 0.15)
				)
				(justify left bottom)
				(hide yes)
			)
		)
		(property "Value" "+3V3"
			(at 160.02 212.09 0)
			(effects
				(font
					(size 1.27 1.27)
					(thickness 0.15)
				)
			)
		)
		(property "Footprint" ""
			(at 175.26 224.79 0)
			(effects
				(font
					(size 1.27 1.27)
					(thickness 0.15)
				)
				(justify left bottom)
				(hide yes)
			)
		)
		(property "Datasheet" ""
			(at 175.26 227.33 0)
			(effects
				(font
					(size 1.27 1.27)
					(thickness 0.15)
				)
				(justify left bottom)
				(hide yes)
			)
		)
		(property "Description" ""
			(at 160.02 217.17 0)
			(effects
				(font
					(size 1.27 1.27)
				)
				(hide yes)
			)
		)
		(property "Author" "Antmicro"
			(at 175.26 219.71 0)
			(effects
				(font
					(size 1.27 1.27)
					(thickness 0.15)
				)
				(justify left bottom)
				(hide yes)
			)
		)
		(property "License" "Apache-2.0"
			(at 175.26 222.25 0)
			(effects
				(font
					(size 1.27 1.27)
					(thickness 0.15)
				)
				(justify left bottom)
				(hide yes)
			)
		)
		(pin "1"
		)
		(instances
			(project "com-express-7-baseboard"
				(path ""
					(reference "#PWR035")
					(unit 1)
				)
			)
		)
	)
	(symbol
		(lib_id "antmicroResistors0402:R_330R_0402")
		(at 299.72 104.14 90)
		(mirror x)
		(unit 1)
		(exclude_from_sim no)
		(in_bom yes)
		(on_board yes)
		(dnp no)
		(property "Reference" "R61"
			(at 298.45 105.41 90)
			(effects
				(font
					(size 1.27 1.27)
					(thickness 0.15)
				)
				(justify left)
			)
		)
		(property "Value" "R_330R_0402"
			(at 312.42 124.46 0)
			(effects
				(font
					(size 1.27 1.27)
					(thickness 0.15)
				)
				(justify left bottom)
				(hide yes)
			)
		)
		(property "Footprint" "antmicro-footprints:R_0402_1005Metric"
			(at 314.96 124.46 0)
			(effects
				(font
					(size 1.27 1.27)
					(thickness 0.15)
				)
				(justify left bottom)
				(hide yes)
			)
		)
		(property "Datasheet" "https://www.bourns.com/docs/product-datasheets/cr.pdf"
			(at 317.5 124.46 0)
			(effects
				(font
					(size 1.27 1.27)
					(thickness 0.15)
				)
				(justify left bottom)
				(hide yes)
			)
		)
		(property "Description" ""
			(at 299.72 104.14 0)
			(effects
				(font
					(size 1.27 1.27)
				)
				(hide yes)
			)
		)
		(property "MPN" "CR0402-FX-3300GLF"
			(at 320.04 124.46 0)
			(effects
				(font
					(size 1.27 1.27)
					(thickness 0.15)
				)
				(justify left bottom)
				(hide yes)
			)
		)
		(property "Manufacturer" "Bourns"
			(at 322.58 124.46 0)
			(effects
				(font
					(size 1.27 1.27)
					(thickness 0.15)
				)
				(justify left bottom)
				(hide yes)
			)
		)
		(property "License" "Apache-2.0"
			(at 325.12 124.46 0)
			(effects
				(font
					(size 1.27 1.27)
					(thickness 0.15)
				)
				(justify left bottom)
				(hide yes)
			)
		)
		(property "Author" "Antmicro"
			(at 327.66 124.46 0)
			(effects
				(font
					(size 1.27 1.27)
					(thickness 0.15)
				)
				(justify left bottom)
				(hide yes)
			)
		)
		(property "Val" "330R"
			(at 298.45 107.95 90)
			(effects
				(font
					(size 1.27 1.27)
					(thickness 0.15)
				)
				(justify left)
			)
		)
		(property "Tolerance" "1%"
			(at 309.88 124.46 0)
			(effects
				(font
					(size 1.27 1.27)
				)
				(justify left bottom)
				(hide yes)
			)
		)
		(property "Public" "False"
			(at 330.2 124.46 0)
			(effects
				(font
					(size 1.27 1.27)
				)
				(justify left bottom)
				(hide yes)
			)
		)
		(pin "1"
		)
		(pin "2"
		)
		(instances
			(project "com-express-7-baseboard"
				(path ""
					(reference "R61")
					(unit 1)
				)
			)
		)
	)
	(symbol
		(lib_id "antmicroResistors0402:R_0R_0402")
		(at 168.91 273.05 90)
		(unit 1)
		(exclude_from_sim no)
		(in_bom yes)
		(on_board yes)
		(dnp no)
		(property "Reference" "R36"
			(at 170.18 269.24 90)
			(effects
				(font
					(size 1.27 1.27)
					(thickness 0.15)
				)
				(justify right)
			)
		)
		(property "Value" "R_0R_0402"
			(at 181.61 252.73 0)
			(effects
				(font
					(size 1.27 1.27)
					(thickness 0.15)
				)
				(justify left bottom)
				(hide yes)
			)
		)
		(property "Footprint" "antmicro-footprints:R_0402_1005Metric"
			(at 184.15 252.73 0)
			(effects
				(font
					(size 1.27 1.27)
					(thickness 0.15)
				)
				(justify left bottom)
				(hide yes)
			)
		)
		(property "Datasheet" "https://industrial.panasonic.com/cdbs/www-data/pdf/RDA0000/AOA0000C301.pdf"
			(at 186.69 252.73 0)
			(effects
				(font
					(size 1.27 1.27)
					(thickness 0.15)
				)
				(justify left bottom)
				(hide yes)
			)
		)
		(property "Description" ""
			(at 168.91 273.05 0)
			(effects
				(font
					(size 1.27 1.27)
				)
				(hide yes)
			)
		)
		(property "MPN" "ERJ2GE0R00X"
			(at 189.23 252.73 0)
			(effects
				(font
					(size 1.27 1.27)
					(thickness 0.15)
				)
				(justify left bottom)
				(hide yes)
			)
		)
		(property "Manufacturer" "Panasonic"
			(at 191.77 252.73 0)
			(effects
				(font
					(size 1.27 1.27)
					(thickness 0.15)
				)
				(justify left bottom)
				(hide yes)
			)
		)
		(property "License" "Apache-2.0"
			(at 194.31 252.73 0)
			(effects
				(font
					(size 1.27 1.27)
					(thickness 0.15)
				)
				(justify left bottom)
				(hide yes)
			)
		)
		(property "Author" "Antmicro"
			(at 196.85 252.73 0)
			(effects
				(font
					(size 1.27 1.27)
					(thickness 0.15)
				)
				(justify left bottom)
				(hide yes)
			)
		)
		(property "Val" "0R"
			(at 170.18 271.78 90)
			(effects
				(font
					(size 1.27 1.27)
					(thickness 0.15)
				)
				(justify right)
			)
		)
		(property "Tolerance" "~"
			(at 179.07 252.73 0)
			(effects
				(font
					(size 1.27 1.27)
				)
				(justify left bottom)
				(hide yes)
			)
		)
		(property "Current" "1A"
			(at 199.39 252.73 0)
			(effects
				(font
					(size 1.27 1.27)
					(thickness 0.15)
				)
				(justify left bottom)
				(hide yes)
			)
		)
		(property "Public" "False"
			(at 199.39 252.73 0)
			(effects
				(font
					(size 1.27 1.27)
				)
				(justify left bottom)
				(hide yes)
			)
		)
		(pin "2"
		)
		(pin "1"
		)
		(instances
			(project "com-express-7-baseboard"
				(path ""
					(reference "R36")
					(unit 1)
				)
			)
		)
	)
	(symbol
		(lib_id "antmicroResistors0402:R_1k_0402")
		(at 242.57 63.5 90)
		(unit 1)
		(exclude_from_sim no)
		(in_bom yes)
		(on_board yes)
		(dnp no)
		(property "Reference" "R53"
			(at 243.84 59.69 90)
			(effects
				(font
					(size 1.27 1.27)
					(thickness 0.15)
				)
				(justify right)
			)
		)
		(property "Value" "R_1k_0402"
			(at 255.27 43.18 0)
			(effects
				(font
					(size 1.27 1.27)
					(thickness 0.15)
				)
				(justify left bottom)
				(hide yes)
			)
		)
		(property "Footprint" "antmicro-footprints:R_0402_1005Metric"
			(at 257.81 43.18 0)
			(effects
				(font
					(size 1.27 1.27)
					(thickness 0.15)
				)
				(justify left bottom)
				(hide yes)
			)
		)
		(property "Datasheet" "https://www.bourns.com/docs/product-datasheets/cr.pdf"
			(at 260.35 43.18 0)
			(effects
				(font
					(size 1.27 1.27)
					(thickness 0.15)
				)
				(justify left bottom)
				(hide yes)
			)
		)
		(property "Description" ""
			(at 242.57 63.5 0)
			(effects
				(font
					(size 1.27 1.27)
				)
				(hide yes)
			)
		)
		(property "MPN" "CR0402-FX-1001GLF"
			(at 262.89 43.18 0)
			(effects
				(font
					(size 1.27 1.27)
					(thickness 0.15)
				)
				(justify left bottom)
				(hide yes)
			)
		)
		(property "Manufacturer" "Bourns"
			(at 265.43 43.18 0)
			(effects
				(font
					(size 1.27 1.27)
					(thickness 0.15)
				)
				(justify left bottom)
				(hide yes)
			)
		)
		(property "License" "Apache-2.0"
			(at 267.97 43.18 0)
			(effects
				(font
					(size 1.27 1.27)
					(thickness 0.15)
				)
				(justify left bottom)
				(hide yes)
			)
		)
		(property "Author" "Antmicro"
			(at 270.51 43.18 0)
			(effects
				(font
					(size 1.27 1.27)
					(thickness 0.15)
				)
				(justify left bottom)
				(hide yes)
			)
		)
		(property "Val" "1k"
			(at 243.84 62.23 90)
			(effects
				(font
					(size 1.27 1.27)
					(thickness 0.15)
				)
				(justify right)
			)
		)
		(property "Tolerance" "1%"
			(at 252.73 43.18 0)
			(effects
				(font
					(size 1.27 1.27)
				)
				(justify left bottom)
				(hide yes)
			)
		)
		(property "Public" "False"
			(at 273.05 43.18 0)
			(effects
				(font
					(size 1.27 1.27)
				)
				(justify left bottom)
				(hide yes)
			)
		)
		(pin "2"
		)
		(pin "1"
		)
		(instances
			(project "com-express-7-baseboard"
				(path ""
					(reference "R53")
					(unit 1)
				)
			)
		)
	)
	(symbol
		(lib_id "antmicroCapacitors0603:C_22u_16V_0603")
		(at 232.41 125.73 90)
		(unit 1)
		(exclude_from_sim no)
		(in_bom yes)
		(on_board yes)
		(dnp no)
		(fields_autoplaced yes)
		(property "Reference" "C23"
			(at 234.95 121.9135 90)
			(effects
				(font
					(size 1.27 1.27)
					(thickness 0.15)
				)
				(justify right)
			)
		)
		(property "Value" "C_22u_16V_0603"
			(at 242.57 105.41 0)
			(effects
				(font
					(size 1.27 1.27)
					(thickness 0.15)
				)
				(justify left bottom)
				(hide yes)
			)
		)
		(property "Footprint" "antmicro-footprints:C_0603_1608Metric"
			(at 245.11 105.41 0)
			(effects
				(font
					(size 1.27 1.27)
					(thickness 0.15)
				)
				(justify left bottom)
				(hide yes)
			)
		)
		(property "Datasheet" "https://product.samsungsem.com/mlcc/CL10A226MO7JZN.do"
			(at 247.65 105.41 0)
			(effects
				(font
					(size 1.27 1.27)
					(thickness 0.15)
				)
				(justify left bottom)
				(hide yes)
			)
		)
		(property "Description" ""
			(at 232.41 125.73 0)
			(effects
				(font
					(size 1.27 1.27)
				)
				(hide yes)
			)
		)
		(property "MPN" "CL10A226MO7JZNC"
			(at 250.19 105.41 0)
			(effects
				(font
					(size 1.27 1.27)
					(thickness 0.15)
				)
				(justify left bottom)
				(hide yes)
			)
		)
		(property "Manufacturer" "Samsung Electro-Mechanics"
			(at 252.73 105.41 0)
			(effects
				(font
					(size 1.27 1.27)
					(thickness 0.15)
				)
				(justify left bottom)
				(hide yes)
			)
		)
		(property "License" "Apache-2.0"
			(at 255.27 105.41 0)
			(effects
				(font
					(size 1.27 1.27)
					(thickness 0.15)
				)
				(justify left bottom)
				(hide yes)
			)
		)
		(property "Author" "Antmicro"
			(at 257.81 105.41 0)
			(effects
				(font
					(size 1.27 1.27)
					(thickness 0.15)
				)
				(justify left bottom)
				(hide yes)
			)
		)
		(property "Val" "22u"
			(at 234.95 124.4535 90)
			(effects
				(font
					(size 1.27 1.27)
					(thickness 0.15)
				)
				(justify right)
			)
		)
		(property "Voltage" "16V"
			(at 260.35 105.41 0)
			(effects
				(font
					(size 1.27 1.27)
				)
				(justify left bottom)
				(hide yes)
			)
		)
		(property "Dielectric" ""
			(at 262.89 105.41 0)
			(effects
				(font
					(size 1.27 1.27)
				)
				(justify left bottom)
				(hide yes)
			)
		)
		(property "Public" "False"
			(at 265.43 105.41 0)
			(effects
				(font
					(size 1.27 1.27)
				)
				(justify left bottom)
				(hide yes)
			)
		)
		(pin "2"
		)
		(pin "1"
		)
		(instances
			(project "com-express-7-baseboard"
				(path ""
					(reference "C23")
					(unit 1)
				)
			)
		)
	)
	(symbol
		(lib_id "antmicropower:+3V3")
		(at 321.31 147.32 0)
		(unit 1)
		(exclude_from_sim no)
		(in_bom yes)
		(on_board yes)
		(dnp no)
		(property "Reference" "#PWR053"
			(at 321.31 151.13 0)
			(effects
				(font
					(size 1.27 1.27)
				)
				(justify left bottom)
				(hide yes)
			)
		)
		(property "Value" "+3V3"
			(at 318.77 143.51 0)
			(effects
				(font
					(size 1.27 1.27)
				)
				(justify left)
			)
		)
		(property "Footprint" ""
			(at 321.31 147.32 0)
			(effects
				(font
					(size 1.27 1.27)
				)
				(justify left bottom)
				(hide yes)
			)
		)
		(property "Datasheet" ""
			(at 321.31 147.32 0)
			(effects
				(font
					(size 1.27 1.27)
				)
				(justify left bottom)
				(hide yes)
			)
		)
		(property "Description" ""
			(at 321.31 147.32 0)
			(effects
				(font
					(size 1.27 1.27)
				)
				(hide yes)
			)
		)
		(property "Author" "Antmicro"
			(at 336.55 149.86 0)
			(effects
				(font
					(size 1.27 1.27)
					(thickness 0.15)
				)
				(justify left bottom)
				(hide yes)
			)
		)
		(property "License" "Apache-2.0"
			(at 336.55 152.4 0)
			(effects
				(font
					(size 1.27 1.27)
					(thickness 0.15)
				)
				(justify left bottom)
				(hide yes)
			)
		)
		(pin "1"
		)
		(instances
			(project "com-express-7-baseboard"
				(path ""
					(reference "#PWR053")
					(unit 1)
				)
			)
		)
	)
	(symbol
		(lib_id "antmicroCapacitors0402:C_100n_0402")
		(at 250.19 125.73 90)
		(unit 1)
		(exclude_from_sim no)
		(in_bom yes)
		(on_board yes)
		(dnp no)
		(fields_autoplaced yes)
		(property "Reference" "C27"
			(at 252.73 121.9136 90)
			(effects
				(font
					(size 1.27 1.27)
					(thickness 0.15)
				)
				(justify right)
			)
		)
		(property "Value" "C_100n_0402"
			(at 260.35 105.41 0)
			(effects
				(font
					(size 1.27 1.27)
					(thickness 0.15)
				)
				(justify left bottom)
				(hide yes)
			)
		)
		(property "Footprint" "antmicro-footprints:C_0402_1005Metric"
			(at 262.89 105.41 0)
			(effects
				(font
					(size 1.27 1.27)
					(thickness 0.15)
				)
				(justify left bottom)
				(hide yes)
			)
		)
		(property "Datasheet" "https://www.murata.com/products/productdetail?partno=GRM155R61H104KE14%23"
			(at 265.43 105.41 0)
			(effects
				(font
					(size 1.27 1.27)
					(thickness 0.15)
				)
				(justify left bottom)
				(hide yes)
			)
		)
		(property "Description" ""
			(at 250.19 125.73 0)
			(effects
				(font
					(size 1.27 1.27)
				)
				(hide yes)
			)
		)
		(property "MPN" "GRM155R61H104KE14D"
			(at 267.97 105.41 0)
			(effects
				(font
					(size 1.27 1.27)
					(thickness 0.15)
				)
				(justify left bottom)
				(hide yes)
			)
		)
		(property "Manufacturer" "Murata"
			(at 270.51 105.41 0)
			(effects
				(font
					(size 1.27 1.27)
					(thickness 0.15)
				)
				(justify left bottom)
				(hide yes)
			)
		)
		(property "License" "Apache-2.0"
			(at 273.05 105.41 0)
			(effects
				(font
					(size 1.27 1.27)
					(thickness 0.15)
				)
				(justify left bottom)
				(hide yes)
			)
		)
		(property "Author" "Antmicro"
			(at 275.59 105.41 0)
			(effects
				(font
					(size 1.27 1.27)
					(thickness 0.15)
				)
				(justify left bottom)
				(hide yes)
			)
		)
		(property "Val" "100n"
			(at 252.73 124.4536 90)
			(effects
				(font
					(size 1.27 1.27)
					(thickness 0.15)
				)
				(justify right)
			)
		)
		(property "Voltage" "50V"
			(at 278.13 105.41 0)
			(effects
				(font
					(size 1.27 1.27)
				)
				(justify left bottom)
				(hide yes)
			)
		)
		(property "Dielectric" "X5R"
			(at 280.67 105.41 0)
			(effects
				(font
					(size 1.27 1.27)
				)
				(justify left bottom)
				(hide yes)
			)
		)
		(property "Public" "False"
			(at 283.21 105.41 0)
			(effects
				(font
					(size 1.27 1.27)
				)
				(justify left bottom)
				(hide yes)
			)
		)
		(pin "2"
		)
		(pin "1"
		)
		(instances
			(project "com-express-7-baseboard"
				(path ""
					(reference "C27")
					(unit 1)
				)
			)
		)
	)
	(symbol
		(lib_id "antmicroResistors0402:R_0R_0402")
		(at 219.71 236.22 0)
		(unit 1)
		(exclude_from_sim no)
		(in_bom yes)
		(on_board yes)
		(dnp no)
		(property "Reference" "R46"
			(at 217.17 234.95 0)
			(effects
				(font
					(size 1.27 1.27)
					(thickness 0.15)
				)
			)
		)
		(property "Value" "R_0R_0402"
			(at 240.03 248.92 0)
			(effects
				(font
					(size 1.27 1.27)
					(thickness 0.15)
				)
				(justify left bottom)
				(hide yes)
			)
		)
		(property "Footprint" "antmicro-footprints:R_0402_1005Metric"
			(at 240.03 251.46 0)
			(effects
				(font
					(size 1.27 1.27)
					(thickness 0.15)
				)
				(justify left bottom)
				(hide yes)
			)
		)
		(property "Datasheet" "https://industrial.panasonic.com/cdbs/www-data/pdf/RDA0000/AOA0000C301.pdf"
			(at 240.03 254 0)
			(effects
				(font
					(size 1.27 1.27)
					(thickness 0.15)
				)
				(justify left bottom)
				(hide yes)
			)
		)
		(property "Description" ""
			(at 219.71 236.22 0)
			(effects
				(font
					(size 1.27 1.27)
				)
				(hide yes)
			)
		)
		(property "MPN" "ERJ2GE0R00X"
			(at 240.03 256.54 0)
			(effects
				(font
					(size 1.27 1.27)
					(thickness 0.15)
				)
				(justify left bottom)
				(hide yes)
			)
		)
		(property "Manufacturer" "Panasonic"
			(at 240.03 259.08 0)
			(effects
				(font
					(size 1.27 1.27)
					(thickness 0.15)
				)
				(justify left bottom)
				(hide yes)
			)
		)
		(property "License" "Apache-2.0"
			(at 240.03 261.62 0)
			(effects
				(font
					(size 1.27 1.27)
					(thickness 0.15)
				)
				(justify left bottom)
				(hide yes)
			)
		)
		(property "Author" "Antmicro"
			(at 240.03 264.16 0)
			(effects
				(font
					(size 1.27 1.27)
					(thickness 0.15)
				)
				(justify left bottom)
				(hide yes)
			)
		)
		(property "Val" "0R"
			(at 226.06 234.95 0)
			(effects
				(font
					(size 1.27 1.27)
					(thickness 0.15)
				)
			)
		)
		(property "Tolerance" "~"
			(at 240.03 246.38 0)
			(effects
				(font
					(size 1.27 1.27)
				)
				(justify left bottom)
				(hide yes)
			)
		)
		(property "Current" "1A"
			(at 240.03 266.7 0)
			(effects
				(font
					(size 1.27 1.27)
					(thickness 0.15)
				)
				(justify left bottom)
				(hide yes)
			)
		)
		(property "Public" "False"
			(at 240.03 266.7 0)
			(effects
				(font
					(size 1.27 1.27)
				)
				(justify left bottom)
				(hide yes)
			)
		)
		(pin "2"
		)
		(pin "1"
		)
		(instances
			(project "com-express-7-baseboard"
				(path ""
					(reference "R46")
					(unit 1)
				)
			)
		)
	)
	(symbol
		(lib_id "antmicroLEDIndicationDiscrete:LED_G_0603_LTST-C190GKT")
		(at 342.9 153.67 270)
		(mirror x)
		(unit 1)
		(exclude_from_sim no)
		(in_bom yes)
		(on_board yes)
		(dnp no)
		(fields_autoplaced yes)
		(property "Reference" "D7"
			(at 346.71 149.86 90)
			(effects
				(font
					(size 1.27 1.27)
				)
				(justify left)
			)
		)
		(property "Value" "LED_G_0603_LTST-C190GKT"
			(at 335.28 130.81 0)
			(effects
				(font
					(size 1.27 1.27)
					(thickness 0.15)
				)
				(justify left bottom)
				(hide yes)
			)
		)
		(property "Footprint" "antmicro-footprints:LED_0603_1608Metric_G"
			(at 332.74 130.81 0)
			(effects
				(font
					(size 1.27 1.27)
					(thickness 0.15)
				)
				(justify left bottom)
				(hide yes)
			)
		)
		(property "Datasheet" "https://media.digikey.com/pdf/Data%20Sheets/Lite-On%20PDFs/LTST-C190GKT.pdf"
			(at 330.2 130.81 0)
			(effects
				(font
					(size 1.27 1.27)
					(thickness 0.15)
				)
				(justify left bottom)
				(hide yes)
			)
		)
		(property "Description" ""
			(at 342.9 153.67 0)
			(effects
				(font
					(size 1.27 1.27)
				)
				(hide yes)
			)
		)
		(property "MPN" "LTST-C190GKT"
			(at 346.71 148.5901 90)
			(effects
				(font
					(size 1.27 1.27)
					(thickness 0.15)
				)
				(justify left)
				(hide yes)
			)
		)
		(property "Manufacturer" "Lite-On"
			(at 325.12 130.81 0)
			(effects
				(font
					(size 1.27 1.27)
					(thickness 0.15)
				)
				(justify left bottom)
				(hide yes)
			)
		)
		(property "Author" "Antmicro"
			(at 322.58 130.81 0)
			(effects
				(font
					(size 1.27 1.27)
					(thickness 0.15)
				)
				(justify left bottom)
				(hide yes)
			)
		)
		(property "License" "Apache-2.0"
			(at 320.04 130.81 0)
			(effects
				(font
					(size 1.27 1.27)
					(thickness 0.15)
				)
				(justify left bottom)
				(hide yes)
			)
		)
		(property "Public" "False"
			(at 325.12 133.35 0)
			(effects
				(font
					(size 1.27 1.27)
				)
				(justify left bottom)
				(hide yes)
			)
		)
		(property "Color" "Green"
			(at 346.71 152.4 90)
			(effects
				(font
					(size 1.27 1.27)
				)
				(justify left)
			)
		)
		(pin "1"
		)
		(pin "2"
		)
		(instances
			(project "com-express-7-baseboard"
				(path ""
					(reference "D7")
					(unit 1)
				)
			)
		)
	)
	(symbol
		(lib_id "antmicroResistors0402:R_0R_0402")
		(at 219.71 241.3 0)
		(unit 1)
		(exclude_from_sim no)
		(in_bom yes)
		(on_board yes)
		(dnp yes)
		(property "Reference" "R48"
			(at 217.17 240.03 0)
			(effects
				(font
					(size 1.27 1.27)
					(thickness 0.15)
				)
			)
		)
		(property "Value" "R_0R_0402"
			(at 240.03 254 0)
			(effects
				(font
					(size 1.27 1.27)
					(thickness 0.15)
				)
				(justify left bottom)
				(hide yes)
			)
		)
		(property "Footprint" "antmicro-footprints:R_0402_1005Metric"
			(at 240.03 256.54 0)
			(effects
				(font
					(size 1.27 1.27)
					(thickness 0.15)
				)
				(justify left bottom)
				(hide yes)
			)
		)
		(property "Datasheet" "https://industrial.panasonic.com/cdbs/www-data/pdf/RDA0000/AOA0000C301.pdf"
			(at 240.03 259.08 0)
			(effects
				(font
					(size 1.27 1.27)
					(thickness 0.15)
				)
				(justify left bottom)
				(hide yes)
			)
		)
		(property "Description" ""
			(at 219.71 241.3 0)
			(effects
				(font
					(size 1.27 1.27)
				)
				(hide yes)
			)
		)
		(property "MPN" "ERJ2GE0R00X"
			(at 240.03 261.62 0)
			(effects
				(font
					(size 1.27 1.27)
					(thickness 0.15)
				)
				(justify left bottom)
				(hide yes)
			)
		)
		(property "Manufacturer" "Panasonic"
			(at 240.03 264.16 0)
			(effects
				(font
					(size 1.27 1.27)
					(thickness 0.15)
				)
				(justify left bottom)
				(hide yes)
			)
		)
		(property "License" "Apache-2.0"
			(at 240.03 266.7 0)
			(effects
				(font
					(size 1.27 1.27)
					(thickness 0.15)
				)
				(justify left bottom)
				(hide yes)
			)
		)
		(property "Author" "Antmicro"
			(at 240.03 269.24 0)
			(effects
				(font
					(size 1.27 1.27)
					(thickness 0.15)
				)
				(justify left bottom)
				(hide yes)
			)
		)
		(property "Val" "0R"
			(at 226.06 240.03 0)
			(effects
				(font
					(size 1.27 1.27)
					(thickness 0.15)
				)
			)
		)
		(property "Tolerance" "~"
			(at 240.03 251.46 0)
			(effects
				(font
					(size 1.27 1.27)
				)
				(justify left bottom)
				(hide yes)
			)
		)
		(property "Current" "1A"
			(at 240.03 271.78 0)
			(effects
				(font
					(size 1.27 1.27)
					(thickness 0.15)
				)
				(justify left bottom)
				(hide yes)
			)
		)
		(property "Public" "False"
			(at 240.03 271.78 0)
			(effects
				(font
					(size 1.27 1.27)
				)
				(justify left bottom)
				(hide yes)
			)
		)
		(pin "2"
		)
		(pin "1"
		)
		(instances
			(project "com-express-7-baseboard"
				(path ""
					(reference "R48")
					(unit 1)
				)
			)
		)
	)
	(symbol
		(lib_id "antmicroResistors0402:R_1k_0402")
		(at 234.95 63.5 90)
		(unit 1)
		(exclude_from_sim no)
		(in_bom yes)
		(on_board yes)
		(dnp no)
		(property "Reference" "R51"
			(at 236.22 59.69 90)
			(effects
				(font
					(size 1.27 1.27)
					(thickness 0.15)
				)
				(justify right)
			)
		)
		(property "Value" "R_1k_0402"
			(at 247.65 43.18 0)
			(effects
				(font
					(size 1.27 1.27)
					(thickness 0.15)
				)
				(justify left bottom)
				(hide yes)
			)
		)
		(property "Footprint" "antmicro-footprints:R_0402_1005Metric"
			(at 250.19 43.18 0)
			(effects
				(font
					(size 1.27 1.27)
					(thickness 0.15)
				)
				(justify left bottom)
				(hide yes)
			)
		)
		(property "Datasheet" "https://www.bourns.com/docs/product-datasheets/cr.pdf"
			(at 252.73 43.18 0)
			(effects
				(font
					(size 1.27 1.27)
					(thickness 0.15)
				)
				(justify left bottom)
				(hide yes)
			)
		)
		(property "Description" ""
			(at 234.95 63.5 0)
			(effects
				(font
					(size 1.27 1.27)
				)
				(hide yes)
			)
		)
		(property "MPN" "CR0402-FX-1001GLF"
			(at 255.27 43.18 0)
			(effects
				(font
					(size 1.27 1.27)
					(thickness 0.15)
				)
				(justify left bottom)
				(hide yes)
			)
		)
		(property "Manufacturer" "Bourns"
			(at 257.81 43.18 0)
			(effects
				(font
					(size 1.27 1.27)
					(thickness 0.15)
				)
				(justify left bottom)
				(hide yes)
			)
		)
		(property "License" "Apache-2.0"
			(at 260.35 43.18 0)
			(effects
				(font
					(size 1.27 1.27)
					(thickness 0.15)
				)
				(justify left bottom)
				(hide yes)
			)
		)
		(property "Author" "Antmicro"
			(at 262.89 43.18 0)
			(effects
				(font
					(size 1.27 1.27)
					(thickness 0.15)
				)
				(justify left bottom)
				(hide yes)
			)
		)
		(property "Val" "1k"
			(at 236.22 62.23 90)
			(effects
				(font
					(size 1.27 1.27)
					(thickness 0.15)
				)
				(justify right)
			)
		)
		(property "Tolerance" "1%"
			(at 245.11 43.18 0)
			(effects
				(font
					(size 1.27 1.27)
				)
				(justify left bottom)
				(hide yes)
			)
		)
		(property "Public" "False"
			(at 265.43 43.18 0)
			(effects
				(font
					(size 1.27 1.27)
				)
				(justify left bottom)
				(hide yes)
			)
		)
		(pin "2"
		)
		(pin "1"
		)
		(instances
			(project "com-express-7-baseboard"
				(path ""
					(reference "R51")
					(unit 1)
				)
			)
		)
	)
	(symbol
		(lib_id "antmicroCapacitors0402:C_100n_0402")
		(at 250.19 41.91 90)
		(unit 1)
		(exclude_from_sim no)
		(in_bom yes)
		(on_board yes)
		(dnp no)
		(fields_autoplaced yes)
		(property "Reference" "C26"
			(at 252.73 38.0936 90)
			(effects
				(font
					(size 1.27 1.27)
					(thickness 0.15)
				)
				(justify right)
			)
		)
		(property "Value" "C_100n_0402"
			(at 260.35 21.59 0)
			(effects
				(font
					(size 1.27 1.27)
					(thickness 0.15)
				)
				(justify left bottom)
				(hide yes)
			)
		)
		(property "Footprint" "antmicro-footprints:C_0402_1005Metric"
			(at 262.89 21.59 0)
			(effects
				(font
					(size 1.27 1.27)
					(thickness 0.15)
				)
				(justify left bottom)
				(hide yes)
			)
		)
		(property "Datasheet" "https://www.murata.com/products/productdetail?partno=GRM155R61H104KE14%23"
			(at 265.43 21.59 0)
			(effects
				(font
					(size 1.27 1.27)
					(thickness 0.15)
				)
				(justify left bottom)
				(hide yes)
			)
		)
		(property "Description" ""
			(at 250.19 41.91 0)
			(effects
				(font
					(size 1.27 1.27)
				)
				(hide yes)
			)
		)
		(property "MPN" "GRM155R61H104KE14D"
			(at 267.97 21.59 0)
			(effects
				(font
					(size 1.27 1.27)
					(thickness 0.15)
				)
				(justify left bottom)
				(hide yes)
			)
		)
		(property "Manufacturer" "Murata"
			(at 270.51 21.59 0)
			(effects
				(font
					(size 1.27 1.27)
					(thickness 0.15)
				)
				(justify left bottom)
				(hide yes)
			)
		)
		(property "License" "Apache-2.0"
			(at 273.05 21.59 0)
			(effects
				(font
					(size 1.27 1.27)
					(thickness 0.15)
				)
				(justify left bottom)
				(hide yes)
			)
		)
		(property "Author" "Antmicro"
			(at 275.59 21.59 0)
			(effects
				(font
					(size 1.27 1.27)
					(thickness 0.15)
				)
				(justify left bottom)
				(hide yes)
			)
		)
		(property "Val" "100n"
			(at 252.73 40.6336 90)
			(effects
				(font
					(size 1.27 1.27)
					(thickness 0.15)
				)
				(justify right)
			)
		)
		(property "Voltage" "50V"
			(at 278.13 21.59 0)
			(effects
				(font
					(size 1.27 1.27)
				)
				(justify left bottom)
				(hide yes)
			)
		)
		(property "Dielectric" "X5R"
			(at 280.67 21.59 0)
			(effects
				(font
					(size 1.27 1.27)
				)
				(justify left bottom)
				(hide yes)
			)
		)
		(property "Public" "False"
			(at 283.21 21.59 0)
			(effects
				(font
					(size 1.27 1.27)
				)
				(justify left bottom)
				(hide yes)
			)
		)
		(pin "2"
		)
		(pin "1"
		)
		(instances
			(project "com-express-7-baseboard"
				(path ""
					(reference "C26")
					(unit 1)
				)
			)
		)
	)
	(symbol
		(lib_id "antmicroCapacitors0402:C_100n_0402")
		(at 241.3 125.73 90)
		(unit 1)
		(exclude_from_sim no)
		(in_bom yes)
		(on_board yes)
		(dnp no)
		(fields_autoplaced yes)
		(property "Reference" "C25"
			(at 243.84 121.9136 90)
			(effects
				(font
					(size 1.27 1.27)
					(thickness 0.15)
				)
				(justify right)
			)
		)
		(property "Value" "C_100n_0402"
			(at 251.46 105.41 0)
			(effects
				(font
					(size 1.27 1.27)
					(thickness 0.15)
				)
				(justify left bottom)
				(hide yes)
			)
		)
		(property "Footprint" "antmicro-footprints:C_0402_1005Metric"
			(at 254 105.41 0)
			(effects
				(font
					(size 1.27 1.27)
					(thickness 0.15)
				)
				(justify left bottom)
				(hide yes)
			)
		)
		(property "Datasheet" "https://www.murata.com/products/productdetail?partno=GRM155R61H104KE14%23"
			(at 256.54 105.41 0)
			(effects
				(font
					(size 1.27 1.27)
					(thickness 0.15)
				)
				(justify left bottom)
				(hide yes)
			)
		)
		(property "Description" ""
			(at 241.3 125.73 0)
			(effects
				(font
					(size 1.27 1.27)
				)
				(hide yes)
			)
		)
		(property "MPN" "GRM155R61H104KE14D"
			(at 259.08 105.41 0)
			(effects
				(font
					(size 1.27 1.27)
					(thickness 0.15)
				)
				(justify left bottom)
				(hide yes)
			)
		)
		(property "Manufacturer" "Murata"
			(at 261.62 105.41 0)
			(effects
				(font
					(size 1.27 1.27)
					(thickness 0.15)
				)
				(justify left bottom)
				(hide yes)
			)
		)
		(property "License" "Apache-2.0"
			(at 264.16 105.41 0)
			(effects
				(font
					(size 1.27 1.27)
					(thickness 0.15)
				)
				(justify left bottom)
				(hide yes)
			)
		)
		(property "Author" "Antmicro"
			(at 266.7 105.41 0)
			(effects
				(font
					(size 1.27 1.27)
					(thickness 0.15)
				)
				(justify left bottom)
				(hide yes)
			)
		)
		(property "Val" "100n"
			(at 243.84 124.4536 90)
			(effects
				(font
					(size 1.27 1.27)
					(thickness 0.15)
				)
				(justify right)
			)
		)
		(property "Voltage" "50V"
			(at 269.24 105.41 0)
			(effects
				(font
					(size 1.27 1.27)
				)
				(justify left bottom)
				(hide yes)
			)
		)
		(property "Dielectric" "X5R"
			(at 271.78 105.41 0)
			(effects
				(font
					(size 1.27 1.27)
				)
				(justify left bottom)
				(hide yes)
			)
		)
		(property "Public" "False"
			(at 274.32 105.41 0)
			(effects
				(font
					(size 1.27 1.27)
				)
				(justify left bottom)
				(hide yes)
			)
		)
		(pin "2"
		)
		(pin "1"
		)
		(instances
			(project "com-express-7-baseboard"
				(path ""
					(reference "C25")
					(unit 1)
				)
			)
		)
	)
	(symbol
		(lib_id "antmicroResistors0402:R_0R_0402")
		(at 219.71 233.68 0)
		(unit 1)
		(exclude_from_sim no)
		(in_bom yes)
		(on_board yes)
		(dnp yes)
		(property "Reference" "R45"
			(at 217.17 232.41 0)
			(effects
				(font
					(size 1.27 1.27)
					(thickness 0.15)
				)
			)
		)
		(property "Value" "R_0R_0402"
			(at 240.03 246.38 0)
			(effects
				(font
					(size 1.27 1.27)
					(thickness 0.15)
				)
				(justify left bottom)
				(hide yes)
			)
		)
		(property "Footprint" "antmicro-footprints:R_0402_1005Metric"
			(at 240.03 248.92 0)
			(effects
				(font
					(size 1.27 1.27)
					(thickness 0.15)
				)
				(justify left bottom)
				(hide yes)
			)
		)
		(property "Datasheet" "https://industrial.panasonic.com/cdbs/www-data/pdf/RDA0000/AOA0000C301.pdf"
			(at 240.03 251.46 0)
			(effects
				(font
					(size 1.27 1.27)
					(thickness 0.15)
				)
				(justify left bottom)
				(hide yes)
			)
		)
		(property "Description" ""
			(at 219.71 233.68 0)
			(effects
				(font
					(size 1.27 1.27)
				)
				(hide yes)
			)
		)
		(property "MPN" "ERJ2GE0R00X"
			(at 240.03 254 0)
			(effects
				(font
					(size 1.27 1.27)
					(thickness 0.15)
				)
				(justify left bottom)
				(hide yes)
			)
		)
		(property "Manufacturer" "Panasonic"
			(at 240.03 256.54 0)
			(effects
				(font
					(size 1.27 1.27)
					(thickness 0.15)
				)
				(justify left bottom)
				(hide yes)
			)
		)
		(property "License" "Apache-2.0"
			(at 240.03 259.08 0)
			(effects
				(font
					(size 1.27 1.27)
					(thickness 0.15)
				)
				(justify left bottom)
				(hide yes)
			)
		)
		(property "Author" "Antmicro"
			(at 240.03 261.62 0)
			(effects
				(font
					(size 1.27 1.27)
					(thickness 0.15)
				)
				(justify left bottom)
				(hide yes)
			)
		)
		(property "Val" "0R"
			(at 226.06 232.41 0)
			(effects
				(font
					(size 1.27 1.27)
					(thickness 0.15)
				)
			)
		)
		(property "Tolerance" "~"
			(at 240.03 243.84 0)
			(effects
				(font
					(size 1.27 1.27)
				)
				(justify left bottom)
				(hide yes)
			)
		)
		(property "Current" "1A"
			(at 240.03 264.16 0)
			(effects
				(font
					(size 1.27 1.27)
					(thickness 0.15)
				)
				(justify left bottom)
				(hide yes)
			)
		)
		(property "Public" "False"
			(at 240.03 264.16 0)
			(effects
				(font
					(size 1.27 1.27)
				)
				(justify left bottom)
				(hide yes)
			)
		)
		(pin "2"
		)
		(pin "1"
		)
		(instances
			(project "com-express-7-baseboard"
				(path ""
					(reference "R45")
					(unit 1)
				)
			)
		)
	)
	(symbol
		(lib_id "antmicroCapacitors0402:C_100n_0402")
		(at 365.76 104.14 90)
		(mirror x)
		(unit 1)
		(exclude_from_sim no)
		(in_bom yes)
		(on_board yes)
		(dnp no)
		(property "Reference" "C214"
			(at 372.11 105.41 90)
			(effects
				(font
					(size 1.27 1.27)
					(thickness 0.15)
				)
				(justify left)
			)
		)
		(property "Value" "C_100n_0402"
			(at 375.92 124.46 0)
			(effects
				(font
					(size 1.27 1.27)
					(thickness 0.15)
				)
				(justify left bottom)
				(hide yes)
			)
		)
		(property "Footprint" "antmicro-footprints:C_0402_1005Metric"
			(at 378.46 124.46 0)
			(effects
				(font
					(size 1.27 1.27)
					(thickness 0.15)
				)
				(justify left bottom)
				(hide yes)
			)
		)
		(property "Datasheet" "https://www.murata.com/products/productdetail?partno=GRM155R61H104KE14%23"
			(at 381 124.46 0)
			(effects
				(font
					(size 1.27 1.27)
					(thickness 0.15)
				)
				(justify left bottom)
				(hide yes)
			)
		)
		(property "Description" ""
			(at 365.76 104.14 0)
			(effects
				(font
					(size 1.27 1.27)
				)
				(hide yes)
			)
		)
		(property "MPN" "GRM155R61H104KE14D"
			(at 383.54 124.46 0)
			(effects
				(font
					(size 1.27 1.27)
					(thickness 0.15)
				)
				(justify left bottom)
				(hide yes)
			)
		)
		(property "Manufacturer" "Murata"
			(at 386.08 124.46 0)
			(effects
				(font
					(size 1.27 1.27)
					(thickness 0.15)
				)
				(justify left bottom)
				(hide yes)
			)
		)
		(property "License" "Apache-2.0"
			(at 388.62 124.46 0)
			(effects
				(font
					(size 1.27 1.27)
					(thickness 0.15)
				)
				(justify left bottom)
				(hide yes)
			)
		)
		(property "Author" "Antmicro"
			(at 391.16 124.46 0)
			(effects
				(font
					(size 1.27 1.27)
					(thickness 0.15)
				)
				(justify left bottom)
				(hide yes)
			)
		)
		(property "Val" "100n"
			(at 372.11 107.95 90)
			(effects
				(font
					(size 1.27 1.27)
					(thickness 0.15)
				)
				(justify left)
			)
		)
		(property "Voltage" "50V"
			(at 393.7 124.46 0)
			(effects
				(font
					(size 1.27 1.27)
				)
				(justify left bottom)
				(hide yes)
			)
		)
		(property "Dielectric" "X5R"
			(at 396.24 124.46 0)
			(effects
				(font
					(size 1.27 1.27)
				)
				(justify left bottom)
				(hide yes)
			)
		)
		(property "Public" "False"
			(at 398.78 124.46 0)
			(effects
				(font
					(size 1.27 1.27)
				)
				(justify left bottom)
				(hide yes)
			)
		)
		(pin "1"
		)
		(pin "2"
		)
		(instances
			(project "com-express-7-baseboard"
				(path ""
					(reference "C214")
					(unit 1)
				)
			)
		)
	)
	(symbol
		(lib_id "antmicroResistors0402:R_0R_0402")
		(at 194.31 68.58 0)
		(unit 1)
		(exclude_from_sim no)
		(in_bom yes)
		(on_board yes)
		(dnp no)
		(property "Reference" "R37"
			(at 191.77 67.31 0)
			(effects
				(font
					(size 1.27 1.27)
					(thickness 0.15)
				)
			)
		)
		(property "Value" "R_0R_0402"
			(at 214.63 81.28 0)
			(effects
				(font
					(size 1.27 1.27)
					(thickness 0.15)
				)
				(justify left bottom)
				(hide yes)
			)
		)
		(property "Footprint" "antmicro-footprints:R_0402_1005Metric"
			(at 214.63 83.82 0)
			(effects
				(font
					(size 1.27 1.27)
					(thickness 0.15)
				)
				(justify left bottom)
				(hide yes)
			)
		)
		(property "Datasheet" "https://industrial.panasonic.com/cdbs/www-data/pdf/RDA0000/AOA0000C301.pdf"
			(at 214.63 86.36 0)
			(effects
				(font
					(size 1.27 1.27)
					(thickness 0.15)
				)
				(justify left bottom)
				(hide yes)
			)
		)
		(property "Description" ""
			(at 194.31 68.58 0)
			(effects
				(font
					(size 1.27 1.27)
				)
				(hide yes)
			)
		)
		(property "MPN" "ERJ2GE0R00X"
			(at 214.63 88.9 0)
			(effects
				(font
					(size 1.27 1.27)
					(thickness 0.15)
				)
				(justify left bottom)
				(hide yes)
			)
		)
		(property "Manufacturer" "Panasonic"
			(at 214.63 91.44 0)
			(effects
				(font
					(size 1.27 1.27)
					(thickness 0.15)
				)
				(justify left bottom)
				(hide yes)
			)
		)
		(property "License" "Apache-2.0"
			(at 214.63 93.98 0)
			(effects
				(font
					(size 1.27 1.27)
					(thickness 0.15)
				)
				(justify left bottom)
				(hide yes)
			)
		)
		(property "Author" "Antmicro"
			(at 214.63 96.52 0)
			(effects
				(font
					(size 1.27 1.27)
					(thickness 0.15)
				)
				(justify left bottom)
				(hide yes)
			)
		)
		(property "Val" "0R"
			(at 200.66 67.31 0)
			(effects
				(font
					(size 1.27 1.27)
					(thickness 0.15)
				)
			)
		)
		(property "Tolerance" "~"
			(at 214.63 78.74 0)
			(effects
				(font
					(size 1.27 1.27)
				)
				(justify left bottom)
				(hide yes)
			)
		)
		(property "Current" "1A"
			(at 214.63 99.06 0)
			(effects
				(font
					(size 1.27 1.27)
					(thickness 0.15)
				)
				(justify left bottom)
				(hide yes)
			)
		)
		(property "Public" "False"
			(at 214.63 99.06 0)
			(effects
				(font
					(size 1.27 1.27)
				)
				(justify left bottom)
				(hide yes)
			)
		)
		(pin "2"
		)
		(pin "1"
		)
		(instances
			(project "com-express-7-baseboard"
				(path ""
					(reference "R37")
					(unit 1)
				)
			)
		)
	)
	(symbol
		(lib_id "antmicropower:GND")
		(at 365.76 114.3 0)
		(mirror y)
		(unit 1)
		(exclude_from_sim no)
		(in_bom yes)
		(on_board yes)
		(dnp no)
		(property "Reference" "#PWR0457"
			(at 356.87 116.84 0)
			(effects
				(font
					(size 1.27 1.27)
					(thickness 0.15)
				)
				(justify left bottom)
				(hide yes)
			)
		)
		(property "Value" "GND"
			(at 365.76 118.11 0)
			(effects
				(font
					(size 1.27 1.27)
					(thickness 0.15)
				)
			)
		)
		(property "Footprint" ""
			(at 356.87 121.92 0)
			(effects
				(font
					(size 1.27 1.27)
					(thickness 0.15)
				)
				(justify left bottom)
				(hide yes)
			)
		)
		(property "Datasheet" ""
			(at 356.87 127 0)
			(effects
				(font
					(size 1.27 1.27)
					(thickness 0.15)
				)
				(justify left bottom)
				(hide yes)
			)
		)
		(property "Description" ""
			(at 365.76 114.3 0)
			(effects
				(font
					(size 1.27 1.27)
				)
				(hide yes)
			)
		)
		(property "Author" "Antmicro"
			(at 356.87 121.92 0)
			(effects
				(font
					(size 1.27 1.27)
					(thickness 0.15)
				)
				(justify left bottom)
				(hide yes)
			)
		)
		(property "License" "Apache-2.0"
			(at 356.87 124.46 0)
			(effects
				(font
					(size 1.27 1.27)
					(thickness 0.15)
				)
				(justify left bottom)
				(hide yes)
			)
		)
		(pin "1"
		)
		(instances
			(project "com-express-7-baseboard"
				(path ""
					(reference "#PWR0457")
					(unit 1)
				)
			)
		)
	)
	(symbol
		(lib_id "antmicroResistors0402:R_0R_0402")
		(at 219.71 238.76 0)
		(unit 1)
		(exclude_from_sim no)
		(in_bom yes)
		(on_board yes)
		(dnp no)
		(property "Reference" "R47"
			(at 217.17 237.49 0)
			(effects
				(font
					(size 1.27 1.27)
					(thickness 0.15)
				)
			)
		)
		(property "Value" "R_0R_0402"
			(at 240.03 251.46 0)
			(effects
				(font
					(size 1.27 1.27)
					(thickness 0.15)
				)
				(justify left bottom)
				(hide yes)
			)
		)
		(property "Footprint" "antmicro-footprints:R_0402_1005Metric"
			(at 240.03 254 0)
			(effects
				(font
					(size 1.27 1.27)
					(thickness 0.15)
				)
				(justify left bottom)
				(hide yes)
			)
		)
		(property "Datasheet" "https://industrial.panasonic.com/cdbs/www-data/pdf/RDA0000/AOA0000C301.pdf"
			(at 240.03 256.54 0)
			(effects
				(font
					(size 1.27 1.27)
					(thickness 0.15)
				)
				(justify left bottom)
				(hide yes)
			)
		)
		(property "Description" ""
			(at 219.71 238.76 0)
			(effects
				(font
					(size 1.27 1.27)
				)
				(hide yes)
			)
		)
		(property "MPN" "ERJ2GE0R00X"
			(at 240.03 259.08 0)
			(effects
				(font
					(size 1.27 1.27)
					(thickness 0.15)
				)
				(justify left bottom)
				(hide yes)
			)
		)
		(property "Manufacturer" "Panasonic"
			(at 240.03 261.62 0)
			(effects
				(font
					(size 1.27 1.27)
					(thickness 0.15)
				)
				(justify left bottom)
				(hide yes)
			)
		)
		(property "License" "Apache-2.0"
			(at 240.03 264.16 0)
			(effects
				(font
					(size 1.27 1.27)
					(thickness 0.15)
				)
				(justify left bottom)
				(hide yes)
			)
		)
		(property "Author" "Antmicro"
			(at 240.03 266.7 0)
			(effects
				(font
					(size 1.27 1.27)
					(thickness 0.15)
				)
				(justify left bottom)
				(hide yes)
			)
		)
		(property "Val" "0R"
			(at 226.06 237.49 0)
			(effects
				(font
					(size 1.27 1.27)
					(thickness 0.15)
				)
			)
		)
		(property "Tolerance" "~"
			(at 240.03 248.92 0)
			(effects
				(font
					(size 1.27 1.27)
				)
				(justify left bottom)
				(hide yes)
			)
		)
		(property "Current" "1A"
			(at 240.03 269.24 0)
			(effects
				(font
					(size 1.27 1.27)
					(thickness 0.15)
				)
				(justify left bottom)
				(hide yes)
			)
		)
		(property "Public" "False"
			(at 240.03 269.24 0)
			(effects
				(font
					(size 1.27 1.27)
				)
				(justify left bottom)
				(hide yes)
			)
		)
		(pin "2"
		)
		(pin "1"
		)
		(instances
			(project "com-express-7-baseboard"
				(path ""
					(reference "R47")
					(unit 1)
				)
			)
		)
	)
	(symbol
		(lib_id "antmicroCapacitors0402:C_100n_0402")
		(at 374.65 104.14 90)
		(mirror x)
		(unit 1)
		(exclude_from_sim no)
		(in_bom yes)
		(on_board yes)
		(dnp no)
		(property "Reference" "C215"
			(at 381 105.41 90)
			(effects
				(font
					(size 1.27 1.27)
					(thickness 0.15)
				)
				(justify left)
			)
		)
		(property "Value" "C_100n_0402"
			(at 384.81 124.46 0)
			(effects
				(font
					(size 1.27 1.27)
					(thickness 0.15)
				)
				(justify left bottom)
				(hide yes)
			)
		)
		(property "Footprint" "antmicro-footprints:C_0402_1005Metric"
			(at 387.35 124.46 0)
			(effects
				(font
					(size 1.27 1.27)
					(thickness 0.15)
				)
				(justify left bottom)
				(hide yes)
			)
		)
		(property "Datasheet" "https://www.murata.com/products/productdetail?partno=GRM155R61H104KE14%23"
			(at 389.89 124.46 0)
			(effects
				(font
					(size 1.27 1.27)
					(thickness 0.15)
				)
				(justify left bottom)
				(hide yes)
			)
		)
		(property "Description" ""
			(at 374.65 104.14 0)
			(effects
				(font
					(size 1.27 1.27)
				)
				(hide yes)
			)
		)
		(property "MPN" "GRM155R61H104KE14D"
			(at 392.43 124.46 0)
			(effects
				(font
					(size 1.27 1.27)
					(thickness 0.15)
				)
				(justify left bottom)
				(hide yes)
			)
		)
		(property "Manufacturer" "Murata"
			(at 394.97 124.46 0)
			(effects
				(font
					(size 1.27 1.27)
					(thickness 0.15)
				)
				(justify left bottom)
				(hide yes)
			)
		)
		(property "License" "Apache-2.0"
			(at 397.51 124.46 0)
			(effects
				(font
					(size 1.27 1.27)
					(thickness 0.15)
				)
				(justify left bottom)
				(hide yes)
			)
		)
		(property "Author" "Antmicro"
			(at 400.05 124.46 0)
			(effects
				(font
					(size 1.27 1.27)
					(thickness 0.15)
				)
				(justify left bottom)
				(hide yes)
			)
		)
		(property "Val" "100n"
			(at 381 107.95 90)
			(effects
				(font
					(size 1.27 1.27)
					(thickness 0.15)
				)
				(justify left)
			)
		)
		(property "Voltage" "50V"
			(at 402.59 124.46 0)
			(effects
				(font
					(size 1.27 1.27)
				)
				(justify left bottom)
				(hide yes)
			)
		)
		(property "Dielectric" "X5R"
			(at 405.13 124.46 0)
			(effects
				(font
					(size 1.27 1.27)
				)
				(justify left bottom)
				(hide yes)
			)
		)
		(property "Public" "False"
			(at 407.67 124.46 0)
			(effects
				(font
					(size 1.27 1.27)
				)
				(justify left bottom)
				(hide yes)
			)
		)
		(pin "1"
		)
		(pin "2"
		)
		(instances
			(project "com-express-7-baseboard"
				(path ""
					(reference "C215")
					(unit 1)
				)
			)
		)
	)
	(symbol
		(lib_id "antmicropower:GND")
		(at 241.3 125.73 0)
		(mirror y)
		(unit 1)
		(exclude_from_sim no)
		(in_bom yes)
		(on_board yes)
		(dnp no)
		(property "Reference" "#PWR045"
			(at 232.41 128.27 0)
			(effects
				(font
					(size 1.27 1.27)
					(thickness 0.15)
				)
				(justify left bottom)
				(hide yes)
			)
		)
		(property "Value" "GND"
			(at 241.3 129.54 0)
			(effects
				(font
					(size 1.27 1.27)
					(thickness 0.15)
				)
			)
		)
		(property "Footprint" ""
			(at 232.41 133.35 0)
			(effects
				(font
					(size 1.27 1.27)
					(thickness 0.15)
				)
				(justify left bottom)
				(hide yes)
			)
		)
		(property "Datasheet" ""
			(at 232.41 138.43 0)
			(effects
				(font
					(size 1.27 1.27)
					(thickness 0.15)
				)
				(justify left bottom)
				(hide yes)
			)
		)
		(property "Description" ""
			(at 241.3 125.73 0)
			(effects
				(font
					(size 1.27 1.27)
				)
				(hide yes)
			)
		)
		(property "Author" "Antmicro"
			(at 232.41 133.35 0)
			(effects
				(font
					(size 1.27 1.27)
					(thickness 0.15)
				)
				(justify left bottom)
				(hide yes)
			)
		)
		(property "License" "Apache-2.0"
			(at 232.41 135.89 0)
			(effects
				(font
					(size 1.27 1.27)
					(thickness 0.15)
				)
				(justify left bottom)
				(hide yes)
			)
		)
		(pin "1"
		)
		(instances
			(project "com-express-7-baseboard"
				(path ""
					(reference "#PWR045")
					(unit 1)
				)
			)
		)
	)
	(symbol
		(lib_id "antmicroResistors0402:R_0R_0402")
		(at 194.31 76.2 0)
		(unit 1)
		(exclude_from_sim no)
		(in_bom yes)
		(on_board yes)
		(dnp no)
		(property "Reference" "R39"
			(at 191.77 74.93 0)
			(effects
				(font
					(size 1.27 1.27)
					(thickness 0.15)
				)
			)
		)
		(property "Value" "R_0R_0402"
			(at 214.63 88.9 0)
			(effects
				(font
					(size 1.27 1.27)
					(thickness 0.15)
				)
				(justify left bottom)
				(hide yes)
			)
		)
		(property "Footprint" "antmicro-footprints:R_0402_1005Metric"
			(at 214.63 91.44 0)
			(effects
				(font
					(size 1.27 1.27)
					(thickness 0.15)
				)
				(justify left bottom)
				(hide yes)
			)
		)
		(property "Datasheet" "https://industrial.panasonic.com/cdbs/www-data/pdf/RDA0000/AOA0000C301.pdf"
			(at 214.63 93.98 0)
			(effects
				(font
					(size 1.27 1.27)
					(thickness 0.15)
				)
				(justify left bottom)
				(hide yes)
			)
		)
		(property "Description" ""
			(at 194.31 76.2 0)
			(effects
				(font
					(size 1.27 1.27)
				)
				(hide yes)
			)
		)
		(property "MPN" "ERJ2GE0R00X"
			(at 214.63 96.52 0)
			(effects
				(font
					(size 1.27 1.27)
					(thickness 0.15)
				)
				(justify left bottom)
				(hide yes)
			)
		)
		(property "Manufacturer" "Panasonic"
			(at 214.63 99.06 0)
			(effects
				(font
					(size 1.27 1.27)
					(thickness 0.15)
				)
				(justify left bottom)
				(hide yes)
			)
		)
		(property "License" "Apache-2.0"
			(at 214.63 101.6 0)
			(effects
				(font
					(size 1.27 1.27)
					(thickness 0.15)
				)
				(justify left bottom)
				(hide yes)
			)
		)
		(property "Author" "Antmicro"
			(at 214.63 104.14 0)
			(effects
				(font
					(size 1.27 1.27)
					(thickness 0.15)
				)
				(justify left bottom)
				(hide yes)
			)
		)
		(property "Val" "0R"
			(at 200.66 74.93 0)
			(effects
				(font
					(size 1.27 1.27)
					(thickness 0.15)
				)
			)
		)
		(property "Tolerance" "~"
			(at 214.63 86.36 0)
			(effects
				(font
					(size 1.27 1.27)
				)
				(justify left bottom)
				(hide yes)
			)
		)
		(property "Current" "1A"
			(at 214.63 106.68 0)
			(effects
				(font
					(size 1.27 1.27)
					(thickness 0.15)
				)
				(justify left bottom)
				(hide yes)
			)
		)
		(property "Public" "False"
			(at 214.63 106.68 0)
			(effects
				(font
					(size 1.27 1.27)
				)
				(justify left bottom)
				(hide yes)
			)
		)
		(pin "2"
		)
		(pin "1"
		)
		(instances
			(project "com-express-7-baseboard"
				(path ""
					(reference "R39")
					(unit 1)
				)
			)
		)
	)
	(symbol
		(lib_id "antmicroResistors0402:R_1k_0402")
		(at 234.95 147.32 90)
		(unit 1)
		(exclude_from_sim no)
		(in_bom yes)
		(on_board yes)
		(dnp no)
		(property "Reference" "R52"
			(at 236.22 143.51 90)
			(effects
				(font
					(size 1.27 1.27)
					(thickness 0.15)
				)
				(justify right)
			)
		)
		(property "Value" "R_1k_0402"
			(at 247.65 127 0)
			(effects
				(font
					(size 1.27 1.27)
					(thickness 0.15)
				)
				(justify left bottom)
				(hide yes)
			)
		)
		(property "Footprint" "antmicro-footprints:R_0402_1005Metric"
			(at 250.19 127 0)
			(effects
				(font
					(size 1.27 1.27)
					(thickness 0.15)
				)
				(justify left bottom)
				(hide yes)
			)
		)
		(property "Datasheet" "https://www.bourns.com/docs/product-datasheets/cr.pdf"
			(at 252.73 127 0)
			(effects
				(font
					(size 1.27 1.27)
					(thickness 0.15)
				)
				(justify left bottom)
				(hide yes)
			)
		)
		(property "Description" ""
			(at 234.95 147.32 0)
			(effects
				(font
					(size 1.27 1.27)
				)
				(hide yes)
			)
		)
		(property "MPN" "CR0402-FX-1001GLF"
			(at 255.27 127 0)
			(effects
				(font
					(size 1.27 1.27)
					(thickness 0.15)
				)
				(justify left bottom)
				(hide yes)
			)
		)
		(property "Manufacturer" "Bourns"
			(at 257.81 127 0)
			(effects
				(font
					(size 1.27 1.27)
					(thickness 0.15)
				)
				(justify left bottom)
				(hide yes)
			)
		)
		(property "License" "Apache-2.0"
			(at 260.35 127 0)
			(effects
				(font
					(size 1.27 1.27)
					(thickness 0.15)
				)
				(justify left bottom)
				(hide yes)
			)
		)
		(property "Author" "Antmicro"
			(at 262.89 127 0)
			(effects
				(font
					(size 1.27 1.27)
					(thickness 0.15)
				)
				(justify left bottom)
				(hide yes)
			)
		)
		(property "Val" "1k"
			(at 236.22 146.05 90)
			(effects
				(font
					(size 1.27 1.27)
					(thickness 0.15)
				)
				(justify right)
			)
		)
		(property "Tolerance" "1%"
			(at 245.11 127 0)
			(effects
				(font
					(size 1.27 1.27)
				)
				(justify left bottom)
				(hide yes)
			)
		)
		(property "Public" "False"
			(at 265.43 127 0)
			(effects
				(font
					(size 1.27 1.27)
				)
				(justify left bottom)
				(hide yes)
			)
		)
		(pin "2"
		)
		(pin "1"
		)
		(instances
			(project "com-express-7-baseboard"
				(path ""
					(reference "R52")
					(unit 1)
				)
			)
		)
	)
	(symbol
		(lib_id "antmicroCapacitors0402:C_100n_0402")
		(at 312.42 104.14 90)
		(mirror x)
		(unit 1)
		(exclude_from_sim no)
		(in_bom yes)
		(on_board yes)
		(dnp no)
		(property "Reference" "C208"
			(at 318.77 105.41 90)
			(effects
				(font
					(size 1.27 1.27)
					(thickness 0.15)
				)
				(justify left)
			)
		)
		(property "Value" "C_100n_0402"
			(at 322.58 124.46 0)
			(effects
				(font
					(size 1.27 1.27)
					(thickness 0.15)
				)
				(justify left bottom)
				(hide yes)
			)
		)
		(property "Footprint" "antmicro-footprints:C_0402_1005Metric"
			(at 325.12 124.46 0)
			(effects
				(font
					(size 1.27 1.27)
					(thickness 0.15)
				)
				(justify left bottom)
				(hide yes)
			)
		)
		(property "Datasheet" "https://www.murata.com/products/productdetail?partno=GRM155R61H104KE14%23"
			(at 327.66 124.46 0)
			(effects
				(font
					(size 1.27 1.27)
					(thickness 0.15)
				)
				(justify left bottom)
				(hide yes)
			)
		)
		(property "Description" ""
			(at 312.42 104.14 0)
			(effects
				(font
					(size 1.27 1.27)
				)
				(hide yes)
			)
		)
		(property "MPN" "GRM155R61H104KE14D"
			(at 330.2 124.46 0)
			(effects
				(font
					(size 1.27 1.27)
					(thickness 0.15)
				)
				(justify left bottom)
				(hide yes)
			)
		)
		(property "Manufacturer" "Murata"
			(at 332.74 124.46 0)
			(effects
				(font
					(size 1.27 1.27)
					(thickness 0.15)
				)
				(justify left bottom)
				(hide yes)
			)
		)
		(property "License" "Apache-2.0"
			(at 335.28 124.46 0)
			(effects
				(font
					(size 1.27 1.27)
					(thickness 0.15)
				)
				(justify left bottom)
				(hide yes)
			)
		)
		(property "Author" "Antmicro"
			(at 337.82 124.46 0)
			(effects
				(font
					(size 1.27 1.27)
					(thickness 0.15)
				)
				(justify left bottom)
				(hide yes)
			)
		)
		(property "Val" "100n"
			(at 318.77 107.95 90)
			(effects
				(font
					(size 1.27 1.27)
					(thickness 0.15)
				)
				(justify left)
			)
		)
		(property "Voltage" "50V"
			(at 340.36 124.46 0)
			(effects
				(font
					(size 1.27 1.27)
				)
				(justify left bottom)
				(hide yes)
			)
		)
		(property "Dielectric" "X5R"
			(at 342.9 124.46 0)
			(effects
				(font
					(size 1.27 1.27)
				)
				(justify left bottom)
				(hide yes)
			)
		)
		(property "Public" "False"
			(at 345.44 124.46 0)
			(effects
				(font
					(size 1.27 1.27)
				)
				(justify left bottom)
				(hide yes)
			)
		)
		(pin "1"
		)
		(pin "2"
		)
		(instances
			(project "com-express-7-baseboard"
				(path ""
					(reference "C208")
					(unit 1)
				)
			)
		)
	)
	(symbol
		(lib_id "antmicroResistors0402:R_1k_0402")
		(at 227.33 147.32 90)
		(unit 1)
		(exclude_from_sim no)
		(in_bom yes)
		(on_board yes)
		(dnp no)
		(property "Reference" "R50"
			(at 228.6 143.51 90)
			(effects
				(font
					(size 1.27 1.27)
					(thickness 0.15)
				)
				(justify right)
			)
		)
		(property "Value" "R_1k_0402"
			(at 240.03 127 0)
			(effects
				(font
					(size 1.27 1.27)
					(thickness 0.15)
				)
				(justify left bottom)
				(hide yes)
			)
		)
		(property "Footprint" "antmicro-footprints:R_0402_1005Metric"
			(at 242.57 127 0)
			(effects
				(font
					(size 1.27 1.27)
					(thickness 0.15)
				)
				(justify left bottom)
				(hide yes)
			)
		)
		(property "Datasheet" "https://www.bourns.com/docs/product-datasheets/cr.pdf"
			(at 245.11 127 0)
			(effects
				(font
					(size 1.27 1.27)
					(thickness 0.15)
				)
				(justify left bottom)
				(hide yes)
			)
		)
		(property "Description" ""
			(at 227.33 147.32 0)
			(effects
				(font
					(size 1.27 1.27)
				)
				(hide yes)
			)
		)
		(property "MPN" "CR0402-FX-1001GLF"
			(at 247.65 127 0)
			(effects
				(font
					(size 1.27 1.27)
					(thickness 0.15)
				)
				(justify left bottom)
				(hide yes)
			)
		)
		(property "Manufacturer" "Bourns"
			(at 250.19 127 0)
			(effects
				(font
					(size 1.27 1.27)
					(thickness 0.15)
				)
				(justify left bottom)
				(hide yes)
			)
		)
		(property "License" "Apache-2.0"
			(at 252.73 127 0)
			(effects
				(font
					(size 1.27 1.27)
					(thickness 0.15)
				)
				(justify left bottom)
				(hide yes)
			)
		)
		(property "Author" "Antmicro"
			(at 255.27 127 0)
			(effects
				(font
					(size 1.27 1.27)
					(thickness 0.15)
				)
				(justify left bottom)
				(hide yes)
			)
		)
		(property "Val" "1k"
			(at 228.6 146.05 90)
			(effects
				(font
					(size 1.27 1.27)
					(thickness 0.15)
				)
				(justify right)
			)
		)
		(property "Tolerance" "1%"
			(at 237.49 127 0)
			(effects
				(font
					(size 1.27 1.27)
				)
				(justify left bottom)
				(hide yes)
			)
		)
		(property "Public" "False"
			(at 257.81 127 0)
			(effects
				(font
					(size 1.27 1.27)
				)
				(justify left bottom)
				(hide yes)
			)
		)
		(pin "2"
		)
		(pin "1"
		)
		(instances
			(project "com-express-7-baseboard"
				(path ""
					(reference "R50")
					(unit 1)
				)
			)
		)
	)
	(symbol
		(lib_id "antmicroResistors0402:R_0R_0402")
		(at 194.31 154.94 0)
		(unit 1)
		(exclude_from_sim no)
		(in_bom yes)
		(on_board yes)
		(dnp no)
		(property "Reference" "R41"
			(at 191.77 153.67 0)
			(effects
				(font
					(size 1.27 1.27)
					(thickness 0.15)
				)
			)
		)
		(property "Value" "R_0R_0402"
			(at 214.63 167.64 0)
			(effects
				(font
					(size 1.27 1.27)
					(thickness 0.15)
				)
				(justify left bottom)
				(hide yes)
			)
		)
		(property "Footprint" "antmicro-footprints:R_0402_1005Metric"
			(at 214.63 170.18 0)
			(effects
				(font
					(size 1.27 1.27)
					(thickness 0.15)
				)
				(justify left bottom)
				(hide yes)
			)
		)
		(property "Datasheet" "https://industrial.panasonic.com/cdbs/www-data/pdf/RDA0000/AOA0000C301.pdf"
			(at 214.63 172.72 0)
			(effects
				(font
					(size 1.27 1.27)
					(thickness 0.15)
				)
				(justify left bottom)
				(hide yes)
			)
		)
		(property "Description" ""
			(at 194.31 154.94 0)
			(effects
				(font
					(size 1.27 1.27)
				)
				(hide yes)
			)
		)
		(property "MPN" "ERJ2GE0R00X"
			(at 214.63 175.26 0)
			(effects
				(font
					(size 1.27 1.27)
					(thickness 0.15)
				)
				(justify left bottom)
				(hide yes)
			)
		)
		(property "Manufacturer" "Panasonic"
			(at 214.63 177.8 0)
			(effects
				(font
					(size 1.27 1.27)
					(thickness 0.15)
				)
				(justify left bottom)
				(hide yes)
			)
		)
		(property "License" "Apache-2.0"
			(at 214.63 180.34 0)
			(effects
				(font
					(size 1.27 1.27)
					(thickness 0.15)
				)
				(justify left bottom)
				(hide yes)
			)
		)
		(property "Author" "Antmicro"
			(at 214.63 182.88 0)
			(effects
				(font
					(size 1.27 1.27)
					(thickness 0.15)
				)
				(justify left bottom)
				(hide yes)
			)
		)
		(property "Val" "0R"
			(at 200.66 153.67 0)
			(effects
				(font
					(size 1.27 1.27)
					(thickness 0.15)
				)
			)
		)
		(property "Tolerance" "~"
			(at 214.63 165.1 0)
			(effects
				(font
					(size 1.27 1.27)
				)
				(justify left bottom)
				(hide yes)
			)
		)
		(property "Current" "1A"
			(at 214.63 185.42 0)
			(effects
				(font
					(size 1.27 1.27)
					(thickness 0.15)
				)
				(justify left bottom)
				(hide yes)
			)
		)
		(property "Public" "False"
			(at 214.63 185.42 0)
			(effects
				(font
					(size 1.27 1.27)
				)
				(justify left bottom)
				(hide yes)
			)
		)
		(pin "2"
		)
		(pin "1"
		)
		(instances
			(project "com-express-7-baseboard"
				(path ""
					(reference "R41")
					(unit 1)
				)
			)
		)
	)
	(symbol
		(lib_id "antmicropower:GND")
		(at 232.41 43.18 0)
		(mirror y)
		(unit 1)
		(exclude_from_sim no)
		(in_bom yes)
		(on_board yes)
		(dnp no)
		(property "Reference" "#PWR041"
			(at 223.52 45.72 0)
			(effects
				(font
					(size 1.27 1.27)
					(thickness 0.15)
				)
				(justify left bottom)
				(hide yes)
			)
		)
		(property "Value" "GND"
			(at 232.41 46.99 0)
			(effects
				(font
					(size 1.27 1.27)
					(thickness 0.15)
				)
			)
		)
		(property "Footprint" ""
			(at 223.52 50.8 0)
			(effects
				(font
					(size 1.27 1.27)
					(thickness 0.15)
				)
				(justify left bottom)
				(hide yes)
			)
		)
		(property "Datasheet" ""
			(at 223.52 55.88 0)
			(effects
				(font
					(size 1.27 1.27)
					(thickness 0.15)
				)
				(justify left bottom)
				(hide yes)
			)
		)
		(property "Description" ""
			(at 232.41 43.18 0)
			(effects
				(font
					(size 1.27 1.27)
				)
				(hide yes)
			)
		)
		(property "Author" "Antmicro"
			(at 223.52 50.8 0)
			(effects
				(font
					(size 1.27 1.27)
					(thickness 0.15)
				)
				(justify left bottom)
				(hide yes)
			)
		)
		(property "License" "Apache-2.0"
			(at 223.52 53.34 0)
			(effects
				(font
					(size 1.27 1.27)
					(thickness 0.15)
				)
				(justify left bottom)
				(hide yes)
			)
		)
		(pin "1"
		)
		(instances
			(project "com-express-7-baseboard"
				(path ""
					(reference "#PWR041")
					(unit 1)
				)
			)
		)
	)
	(symbol
		(lib_id "antmicroResistors0402:R_220R_0402")
		(at 342.9 161.29 90)
		(unit 1)
		(exclude_from_sim no)
		(in_bom yes)
		(on_board yes)
		(dnp no)
		(property "Reference" "R64"
			(at 344.17 157.48 90)
			(effects
				(font
					(size 1.27 1.27)
					(thickness 0.15)
				)
				(justify right)
			)
		)
		(property "Value" "R_220R_0402"
			(at 355.6 140.97 0)
			(effects
				(font
					(size 1.27 1.27)
					(thickness 0.15)
				)
				(justify left bottom)
				(hide yes)
			)
		)
		(property "Footprint" "antmicro-footprints:R_0402_1005Metric"
			(at 358.14 140.97 0)
			(effects
				(font
					(size 1.27 1.27)
					(thickness 0.15)
				)
				(justify left bottom)
				(hide yes)
			)
		)
		(property "Datasheet" "https://www.bourns.com/docs/product-datasheets/cr.pdf"
			(at 360.68 140.97 0)
			(effects
				(font
					(size 1.27 1.27)
					(thickness 0.15)
				)
				(justify left bottom)
				(hide yes)
			)
		)
		(property "Description" ""
			(at 342.9 161.29 0)
			(effects
				(font
					(size 1.27 1.27)
				)
				(hide yes)
			)
		)
		(property "MPN" "CR0402-FX-2200GLF"
			(at 363.22 140.97 0)
			(effects
				(font
					(size 1.27 1.27)
					(thickness 0.15)
				)
				(justify left bottom)
				(hide yes)
			)
		)
		(property "Manufacturer" "Bourns"
			(at 365.76 140.97 0)
			(effects
				(font
					(size 1.27 1.27)
					(thickness 0.15)
				)
				(justify left bottom)
				(hide yes)
			)
		)
		(property "License" "Apache-2.0"
			(at 368.3 140.97 0)
			(effects
				(font
					(size 1.27 1.27)
					(thickness 0.15)
				)
				(justify left bottom)
				(hide yes)
			)
		)
		(property "Author" "Antmicro"
			(at 370.84 140.97 0)
			(effects
				(font
					(size 1.27 1.27)
					(thickness 0.15)
				)
				(justify left bottom)
				(hide yes)
			)
		)
		(property "Val" "220R"
			(at 344.17 160.02 90)
			(effects
				(font
					(size 1.27 1.27)
					(thickness 0.15)
				)
				(justify right)
			)
		)
		(property "Tolerance" "1%"
			(at 353.06 140.97 0)
			(effects
				(font
					(size 1.27 1.27)
				)
				(justify left bottom)
				(hide yes)
			)
		)
		(property "Public" "False"
			(at 373.38 140.97 0)
			(effects
				(font
					(size 1.27 1.27)
				)
				(justify left bottom)
				(hide yes)
			)
		)
		(pin "2"
		)
		(pin "1"
		)
		(instances
			(project "com-express-7-baseboard"
				(path ""
					(reference "R64")
					(unit 1)
				)
			)
		)
	)
	(symbol
		(lib_id "antmicroResistors0402:R_220R_0402")
		(at 322.58 85.09 90)
		(unit 1)
		(exclude_from_sim no)
		(in_bom yes)
		(on_board yes)
		(dnp no)
		(property "Reference" "R63"
			(at 323.85 81.28 90)
			(effects
				(font
					(size 1.27 1.27)
					(thickness 0.15)
				)
				(justify right)
			)
		)
		(property "Value" "R_220R_0402"
			(at 335.28 64.77 0)
			(effects
				(font
					(size 1.27 1.27)
					(thickness 0.15)
				)
				(justify left bottom)
				(hide yes)
			)
		)
		(property "Footprint" "antmicro-footprints:R_0402_1005Metric"
			(at 337.82 64.77 0)
			(effects
				(font
					(size 1.27 1.27)
					(thickness 0.15)
				)
				(justify left bottom)
				(hide yes)
			)
		)
		(property "Datasheet" "https://www.bourns.com/docs/product-datasheets/cr.pdf"
			(at 340.36 64.77 0)
			(effects
				(font
					(size 1.27 1.27)
					(thickness 0.15)
				)
				(justify left bottom)
				(hide yes)
			)
		)
		(property "Description" ""
			(at 322.58 85.09 0)
			(effects
				(font
					(size 1.27 1.27)
				)
				(hide yes)
			)
		)
		(property "MPN" "CR0402-FX-2200GLF"
			(at 342.9 64.77 0)
			(effects
				(font
					(size 1.27 1.27)
					(thickness 0.15)
				)
				(justify left bottom)
				(hide yes)
			)
		)
		(property "Manufacturer" "Bourns"
			(at 345.44 64.77 0)
			(effects
				(font
					(size 1.27 1.27)
					(thickness 0.15)
				)
				(justify left bottom)
				(hide yes)
			)
		)
		(property "License" "Apache-2.0"
			(at 347.98 64.77 0)
			(effects
				(font
					(size 1.27 1.27)
					(thickness 0.15)
				)
				(justify left bottom)
				(hide yes)
			)
		)
		(property "Author" "Antmicro"
			(at 350.52 64.77 0)
			(effects
				(font
					(size 1.27 1.27)
					(thickness 0.15)
				)
				(justify left bottom)
				(hide yes)
			)
		)
		(property "Val" "220R"
			(at 323.85 83.82 90)
			(effects
				(font
					(size 1.27 1.27)
					(thickness 0.15)
				)
				(justify right)
			)
		)
		(property "Tolerance" "1%"
			(at 332.74 64.77 0)
			(effects
				(font
					(size 1.27 1.27)
				)
				(justify left bottom)
				(hide yes)
			)
		)
		(property "Public" "False"
			(at 353.06 64.77 0)
			(effects
				(font
					(size 1.27 1.27)
				)
				(justify left bottom)
				(hide yes)
			)
		)
		(pin "2"
		)
		(pin "1"
		)
		(instances
			(project "com-express-7-baseboard"
				(path ""
					(reference "R63")
					(unit 1)
				)
			)
		)
	)
	(symbol
		(lib_id "antmicroResistors0402:R_0R_0402")
		(at 256.54 86.36 180)
		(unit 1)
		(exclude_from_sim no)
		(in_bom yes)
		(on_board yes)
		(dnp no)
		(property "Reference" "R58"
			(at 259.08 85.09 0)
			(effects
				(font
					(size 1.27 1.27)
					(thickness 0.15)
				)
			)
		)
		(property "Value" "R_0R_0402"
			(at 236.22 73.66 0)
			(effects
				(font
					(size 1.27 1.27)
					(thickness 0.15)
				)
				(justify left bottom)
				(hide yes)
			)
		)
		(property "Footprint" "antmicro-footprints:R_0402_1005Metric"
			(at 236.22 71.12 0)
			(effects
				(font
					(size 1.27 1.27)
					(thickness 0.15)
				)
				(justify left bottom)
				(hide yes)
			)
		)
		(property "Datasheet" "https://industrial.panasonic.com/cdbs/www-data/pdf/RDA0000/AOA0000C301.pdf"
			(at 236.22 68.58 0)
			(effects
				(font
					(size 1.27 1.27)
					(thickness 0.15)
				)
				(justify left bottom)
				(hide yes)
			)
		)
		(property "Description" ""
			(at 256.54 86.36 0)
			(effects
				(font
					(size 1.27 1.27)
				)
				(hide yes)
			)
		)
		(property "MPN" "ERJ2GE0R00X"
			(at 236.22 66.04 0)
			(effects
				(font
					(size 1.27 1.27)
					(thickness 0.15)
				)
				(justify left bottom)
				(hide yes)
			)
		)
		(property "Manufacturer" "Panasonic"
			(at 236.22 63.5 0)
			(effects
				(font
					(size 1.27 1.27)
					(thickness 0.15)
				)
				(justify left bottom)
				(hide yes)
			)
		)
		(property "License" "Apache-2.0"
			(at 236.22 60.96 0)
			(effects
				(font
					(size 1.27 1.27)
					(thickness 0.15)
				)
				(justify left bottom)
				(hide yes)
			)
		)
		(property "Author" "Antmicro"
			(at 236.22 58.42 0)
			(effects
				(font
					(size 1.27 1.27)
					(thickness 0.15)
				)
				(justify left bottom)
				(hide yes)
			)
		)
		(property "Val" "0R"
			(at 250.19 85.09 0)
			(effects
				(font
					(size 1.27 1.27)
					(thickness 0.15)
				)
			)
		)
		(property "Tolerance" "~"
			(at 236.22 76.2 0)
			(effects
				(font
					(size 1.27 1.27)
				)
				(justify left bottom)
				(hide yes)
			)
		)
		(property "Current" "1A"
			(at 236.22 55.88 0)
			(effects
				(font
					(size 1.27 1.27)
					(thickness 0.15)
				)
				(justify left bottom)
				(hide yes)
			)
		)
		(property "Public" "False"
			(at 236.22 55.88 0)
			(effects
				(font
					(size 1.27 1.27)
				)
				(justify left bottom)
				(hide yes)
			)
		)
		(pin "2"
		)
		(pin "1"
		)
		(instances
			(project "com-express-7-baseboard"
				(path ""
					(reference "R58")
					(unit 1)
				)
			)
		)
	)
	(symbol
		(lib_id "antmicropower:GND")
		(at 168.91 274.32 0)
		(unit 1)
		(exclude_from_sim no)
		(in_bom yes)
		(on_board yes)
		(dnp no)
		(property "Reference" "#PWR038"
			(at 177.8 276.86 0)
			(effects
				(font
					(size 1.27 1.27)
					(thickness 0.15)
				)
				(justify left bottom)
				(hide yes)
			)
		)
		(property "Value" "GND"
			(at 168.91 278.13 0)
			(effects
				(font
					(size 1.27 1.27)
					(thickness 0.15)
				)
			)
		)
		(property "Footprint" ""
			(at 177.8 281.94 0)
			(effects
				(font
					(size 1.27 1.27)
					(thickness 0.15)
				)
				(justify left bottom)
				(hide yes)
			)
		)
		(property "Datasheet" ""
			(at 177.8 287.02 0)
			(effects
				(font
					(size 1.27 1.27)
					(thickness 0.15)
				)
				(justify left bottom)
				(hide yes)
			)
		)
		(property "Description" ""
			(at 168.91 274.32 0)
			(effects
				(font
					(size 1.27 1.27)
				)
				(hide yes)
			)
		)
		(property "Author" "Antmicro"
			(at 177.8 281.94 0)
			(effects
				(font
					(size 1.27 1.27)
					(thickness 0.15)
				)
				(justify left bottom)
				(hide yes)
			)
		)
		(property "License" "Apache-2.0"
			(at 177.8 284.48 0)
			(effects
				(font
					(size 1.27 1.27)
					(thickness 0.15)
				)
				(justify left bottom)
				(hide yes)
			)
		)
		(pin "1"
		)
		(instances
			(project "com-express-7-baseboard"
				(path ""
					(reference "#PWR038")
					(unit 1)
				)
			)
		)
	)
	(symbol
		(lib_id "antmicroResistors0402:R_0R_0402")
		(at 194.31 152.4 0)
		(unit 1)
		(exclude_from_sim no)
		(in_bom yes)
		(on_board yes)
		(dnp no)
		(property "Reference" "R40"
			(at 191.77 151.13 0)
			(effects
				(font
					(size 1.27 1.27)
					(thickness 0.15)
				)
			)
		)
		(property "Value" "R_0R_0402"
			(at 214.63 165.1 0)
			(effects
				(font
					(size 1.27 1.27)
					(thickness 0.15)
				)
				(justify left bottom)
				(hide yes)
			)
		)
		(property "Footprint" "antmicro-footprints:R_0402_1005Metric"
			(at 214.63 167.64 0)
			(effects
				(font
					(size 1.27 1.27)
					(thickness 0.15)
				)
				(justify left bottom)
				(hide yes)
			)
		)
		(property "Datasheet" "https://industrial.panasonic.com/cdbs/www-data/pdf/RDA0000/AOA0000C301.pdf"
			(at 214.63 170.18 0)
			(effects
				(font
					(size 1.27 1.27)
					(thickness 0.15)
				)
				(justify left bottom)
				(hide yes)
			)
		)
		(property "Description" ""
			(at 194.31 152.4 0)
			(effects
				(font
					(size 1.27 1.27)
				)
				(hide yes)
			)
		)
		(property "MPN" "ERJ2GE0R00X"
			(at 214.63 172.72 0)
			(effects
				(font
					(size 1.27 1.27)
					(thickness 0.15)
				)
				(justify left bottom)
				(hide yes)
			)
		)
		(property "Manufacturer" "Panasonic"
			(at 214.63 175.26 0)
			(effects
				(font
					(size 1.27 1.27)
					(thickness 0.15)
				)
				(justify left bottom)
				(hide yes)
			)
		)
		(property "License" "Apache-2.0"
			(at 214.63 177.8 0)
			(effects
				(font
					(size 1.27 1.27)
					(thickness 0.15)
				)
				(justify left bottom)
				(hide yes)
			)
		)
		(property "Author" "Antmicro"
			(at 214.63 180.34 0)
			(effects
				(font
					(size 1.27 1.27)
					(thickness 0.15)
				)
				(justify left bottom)
				(hide yes)
			)
		)
		(property "Val" "0R"
			(at 200.66 151.13 0)
			(effects
				(font
					(size 1.27 1.27)
					(thickness 0.15)
				)
			)
		)
		(property "Tolerance" "~"
			(at 214.63 162.56 0)
			(effects
				(font
					(size 1.27 1.27)
				)
				(justify left bottom)
				(hide yes)
			)
		)
		(property "Current" "1A"
			(at 214.63 182.88 0)
			(effects
				(font
					(size 1.27 1.27)
					(thickness 0.15)
				)
				(justify left bottom)
				(hide yes)
			)
		)
		(property "Public" "False"
			(at 214.63 182.88 0)
			(effects
				(font
					(size 1.27 1.27)
				)
				(justify left bottom)
				(hide yes)
			)
		)
		(pin "2"
		)
		(pin "1"
		)
		(instances
			(project "com-express-7-baseboard"
				(path ""
					(reference "R40")
					(unit 1)
				)
			)
		)
	)
	(symbol
		(lib_id "antmicroTestPoints:TP_0.75mm_SMD")
		(at 233.68 165.1 180)
		(unit 1)
		(exclude_from_sim no)
		(in_bom no)
		(on_board yes)
		(dnp no)
		(property "Reference" "TP4"
			(at 224.79 165.1 0)
			(effects
				(font
					(size 1.27 1.27)
					(thickness 0.15)
				)
			)
		)
		(property "Value" "TP_0.75mm_SMD"
			(at 222.885 161.29 0)
			(effects
				(font
					(size 1.27 1.27)
					(thickness 0.15)
				)
				(justify left bottom)
				(hide yes)
			)
		)
		(property "Footprint" "antmicro-footprints:TP_SMD_0.75mm"
			(at 222.885 158.75 0)
			(effects
				(font
					(size 1.27 1.27)
					(thickness 0.15)
				)
				(justify left bottom)
				(hide yes)
			)
		)
		(property "Datasheet" ""
			(at 215.9 152.4 0)
			(effects
				(font
					(size 1.27 1.27)
					(thickness 0.15)
				)
				(justify left bottom)
				(hide yes)
			)
		)
		(property "Description" ""
			(at 233.68 165.1 0)
			(effects
				(font
					(size 1.27 1.27)
				)
				(hide yes)
			)
		)
		(property "MPN" ""
			(at 222.885 153.67 0)
			(effects
				(font
					(size 1.27 1.27)
					(thickness 0.15)
				)
				(justify left bottom)
				(hide yes)
			)
		)
		(property "Manufacturer" ""
			(at 222.885 158.75 0)
			(effects
				(font
					(size 1.27 1.27)
					(thickness 0.15)
				)
				(justify left bottom)
				(hide yes)
			)
		)
		(property "Author" "Antmicro"
			(at 222.885 156.21 0)
			(effects
				(font
					(size 1.27 1.27)
					(thickness 0.15)
				)
				(justify left bottom)
				(hide yes)
			)
		)
		(property "License" "Apache-2.0"
			(at 222.885 153.67 0)
			(effects
				(font
					(size 1.27 1.27)
					(thickness 0.15)
				)
				(justify left bottom)
				(hide yes)
			)
		)
		(property "Public" "False"
			(at 223.52 151.13 0)
			(effects
				(font
					(size 1.27 1.27)
				)
				(justify left bottom)
				(hide yes)
			)
		)
		(pin "1"
		)
		(instances
			(project "com-express-7-baseboard"
				(path ""
					(reference "TP4")
					(unit 1)
				)
			)
		)
	)
	(symbol
		(lib_id "antmicroResistors0402:R_1k_0402")
		(at 250.19 63.5 90)
		(unit 1)
		(exclude_from_sim no)
		(in_bom yes)
		(on_board yes)
		(dnp no)
		(property "Reference" "R55"
			(at 251.46 59.69 90)
			(effects
				(font
					(size 1.27 1.27)
					(thickness 0.15)
				)
				(justify right)
			)
		)
		(property "Value" "R_1k_0402"
			(at 262.89 43.18 0)
			(effects
				(font
					(size 1.27 1.27)
					(thickness 0.15)
				)
				(justify left bottom)
				(hide yes)
			)
		)
		(property "Footprint" "antmicro-footprints:R_0402_1005Metric"
			(at 265.43 43.18 0)
			(effects
				(font
					(size 1.27 1.27)
					(thickness 0.15)
				)
				(justify left bottom)
				(hide yes)
			)
		)
		(property "Datasheet" "https://www.bourns.com/docs/product-datasheets/cr.pdf"
			(at 267.97 43.18 0)
			(effects
				(font
					(size 1.27 1.27)
					(thickness 0.15)
				)
				(justify left bottom)
				(hide yes)
			)
		)
		(property "Description" ""
			(at 250.19 63.5 0)
			(effects
				(font
					(size 1.27 1.27)
				)
				(hide yes)
			)
		)
		(property "MPN" "CR0402-FX-1001GLF"
			(at 270.51 43.18 0)
			(effects
				(font
					(size 1.27 1.27)
					(thickness 0.15)
				)
				(justify left bottom)
				(hide yes)
			)
		)
		(property "Manufacturer" "Bourns"
			(at 273.05 43.18 0)
			(effects
				(font
					(size 1.27 1.27)
					(thickness 0.15)
				)
				(justify left bottom)
				(hide yes)
			)
		)
		(property "License" "Apache-2.0"
			(at 275.59 43.18 0)
			(effects
				(font
					(size 1.27 1.27)
					(thickness 0.15)
				)
				(justify left bottom)
				(hide yes)
			)
		)
		(property "Author" "Antmicro"
			(at 278.13 43.18 0)
			(effects
				(font
					(size 1.27 1.27)
					(thickness 0.15)
				)
				(justify left bottom)
				(hide yes)
			)
		)
		(property "Val" "1k"
			(at 251.46 62.23 90)
			(effects
				(font
					(size 1.27 1.27)
					(thickness 0.15)
				)
				(justify right)
			)
		)
		(property "Tolerance" "1%"
			(at 260.35 43.18 0)
			(effects
				(font
					(size 1.27 1.27)
				)
				(justify left bottom)
				(hide yes)
			)
		)
		(property "Public" "False"
			(at 280.67 43.18 0)
			(effects
				(font
					(size 1.27 1.27)
				)
				(justify left bottom)
				(hide yes)
			)
		)
		(pin "2"
		)
		(pin "1"
		)
		(instances
			(project "com-express-7-baseboard"
				(path ""
					(reference "R55")
					(unit 1)
				)
			)
		)
	)
	(symbol
		(lib_id "antmicroResistors0402:R_0R_0402")
		(at 160.02 273.05 90)
		(unit 1)
		(exclude_from_sim no)
		(in_bom yes)
		(on_board yes)
		(dnp yes)
		(property "Reference" "R32"
			(at 161.29 269.24 90)
			(effects
				(font
					(size 1.27 1.27)
					(thickness 0.15)
				)
				(justify right)
			)
		)
		(property "Value" "R_0R_0402"
			(at 172.72 252.73 0)
			(effects
				(font
					(size 1.27 1.27)
					(thickness 0.15)
				)
				(justify left bottom)
				(hide yes)
			)
		)
		(property "Footprint" "antmicro-footprints:R_0402_1005Metric"
			(at 175.26 252.73 0)
			(effects
				(font
					(size 1.27 1.27)
					(thickness 0.15)
				)
				(justify left bottom)
				(hide yes)
			)
		)
		(property "Datasheet" "https://industrial.panasonic.com/cdbs/www-data/pdf/RDA0000/AOA0000C301.pdf"
			(at 177.8 252.73 0)
			(effects
				(font
					(size 1.27 1.27)
					(thickness 0.15)
				)
				(justify left bottom)
				(hide yes)
			)
		)
		(property "Description" ""
			(at 160.02 273.05 0)
			(effects
				(font
					(size 1.27 1.27)
				)
				(hide yes)
			)
		)
		(property "MPN" "ERJ2GE0R00X"
			(at 180.34 252.73 0)
			(effects
				(font
					(size 1.27 1.27)
					(thickness 0.15)
				)
				(justify left bottom)
				(hide yes)
			)
		)
		(property "Manufacturer" "Panasonic"
			(at 182.88 252.73 0)
			(effects
				(font
					(size 1.27 1.27)
					(thickness 0.15)
				)
				(justify left bottom)
				(hide yes)
			)
		)
		(property "License" "Apache-2.0"
			(at 185.42 252.73 0)
			(effects
				(font
					(size 1.27 1.27)
					(thickness 0.15)
				)
				(justify left bottom)
				(hide yes)
			)
		)
		(property "Author" "Antmicro"
			(at 187.96 252.73 0)
			(effects
				(font
					(size 1.27 1.27)
					(thickness 0.15)
				)
				(justify left bottom)
				(hide yes)
			)
		)
		(property "Val" "0R"
			(at 161.29 271.78 90)
			(effects
				(font
					(size 1.27 1.27)
					(thickness 0.15)
				)
				(justify right)
			)
		)
		(property "Tolerance" "~"
			(at 170.18 252.73 0)
			(effects
				(font
					(size 1.27 1.27)
				)
				(justify left bottom)
				(hide yes)
			)
		)
		(property "Current" "1A"
			(at 190.5 252.73 0)
			(effects
				(font
					(size 1.27 1.27)
					(thickness 0.15)
				)
				(justify left bottom)
				(hide yes)
			)
		)
		(property "Public" "False"
			(at 190.5 252.73 0)
			(effects
				(font
					(size 1.27 1.27)
				)
				(justify left bottom)
				(hide yes)
			)
		)
		(pin "2"
		)
		(pin "1"
		)
		(instances
			(project "com-express-7-baseboard"
				(path ""
					(reference "R32")
					(unit 1)
				)
			)
		)
	)
	(symbol
		(lib_id "antmicropower:GND")
		(at 374.65 114.3 0)
		(mirror y)
		(unit 1)
		(exclude_from_sim no)
		(in_bom yes)
		(on_board yes)
		(dnp no)
		(property "Reference" "#PWR0458"
			(at 365.76 116.84 0)
			(effects
				(font
					(size 1.27 1.27)
					(thickness 0.15)
				)
				(justify left bottom)
				(hide yes)
			)
		)
		(property "Value" "GND"
			(at 374.65 118.11 0)
			(effects
				(font
					(size 1.27 1.27)
					(thickness 0.15)
				)
			)
		)
		(property "Footprint" ""
			(at 365.76 121.92 0)
			(effects
				(font
					(size 1.27 1.27)
					(thickness 0.15)
				)
				(justify left bottom)
				(hide yes)
			)
		)
		(property "Datasheet" ""
			(at 365.76 127 0)
			(effects
				(font
					(size 1.27 1.27)
					(thickness 0.15)
				)
				(justify left bottom)
				(hide yes)
			)
		)
		(property "Description" ""
			(at 374.65 114.3 0)
			(effects
				(font
					(size 1.27 1.27)
				)
				(hide yes)
			)
		)
		(property "Author" "Antmicro"
			(at 365.76 121.92 0)
			(effects
				(font
					(size 1.27 1.27)
					(thickness 0.15)
				)
				(justify left bottom)
				(hide yes)
			)
		)
		(property "License" "Apache-2.0"
			(at 365.76 124.46 0)
			(effects
				(font
					(size 1.27 1.27)
					(thickness 0.15)
				)
				(justify left bottom)
				(hide yes)
			)
		)
		(pin "1"
		)
		(instances
			(project "com-express-7-baseboard"
				(path ""
					(reference "#PWR0458")
					(unit 1)
				)
			)
		)
	)
	(symbol
		(lib_id "antmicroResistors0402:R_1k_0402")
		(at 242.57 147.32 90)
		(unit 1)
		(exclude_from_sim no)
		(in_bom yes)
		(on_board yes)
		(dnp no)
		(property "Reference" "R54"
			(at 243.84 143.51 90)
			(effects
				(font
					(size 1.27 1.27)
					(thickness 0.15)
				)
				(justify right)
			)
		)
		(property "Value" "R_1k_0402"
			(at 255.27 127 0)
			(effects
				(font
					(size 1.27 1.27)
					(thickness 0.15)
				)
				(justify left bottom)
				(hide yes)
			)
		)
		(property "Footprint" "antmicro-footprints:R_0402_1005Metric"
			(at 257.81 127 0)
			(effects
				(font
					(size 1.27 1.27)
					(thickness 0.15)
				)
				(justify left bottom)
				(hide yes)
			)
		)
		(property "Datasheet" "https://www.bourns.com/docs/product-datasheets/cr.pdf"
			(at 260.35 127 0)
			(effects
				(font
					(size 1.27 1.27)
					(thickness 0.15)
				)
				(justify left bottom)
				(hide yes)
			)
		)
		(property "Description" ""
			(at 242.57 147.32 0)
			(effects
				(font
					(size 1.27 1.27)
				)
				(hide yes)
			)
		)
		(property "MPN" "CR0402-FX-1001GLF"
			(at 262.89 127 0)
			(effects
				(font
					(size 1.27 1.27)
					(thickness 0.15)
				)
				(justify left bottom)
				(hide yes)
			)
		)
		(property "Manufacturer" "Bourns"
			(at 265.43 127 0)
			(effects
				(font
					(size 1.27 1.27)
					(thickness 0.15)
				)
				(justify left bottom)
				(hide yes)
			)
		)
		(property "License" "Apache-2.0"
			(at 267.97 127 0)
			(effects
				(font
					(size 1.27 1.27)
					(thickness 0.15)
				)
				(justify left bottom)
				(hide yes)
			)
		)
		(property "Author" "Antmicro"
			(at 270.51 127 0)
			(effects
				(font
					(size 1.27 1.27)
					(thickness 0.15)
				)
				(justify left bottom)
				(hide yes)
			)
		)
		(property "Val" "1k"
			(at 243.84 146.05 90)
			(effects
				(font
					(size 1.27 1.27)
					(thickness 0.15)
				)
				(justify right)
			)
		)
		(property "Tolerance" "1%"
			(at 252.73 127 0)
			(effects
				(font
					(size 1.27 1.27)
				)
				(justify left bottom)
				(hide yes)
			)
		)
		(property "Public" "False"
			(at 273.05 127 0)
			(effects
				(font
					(size 1.27 1.27)
				)
				(justify left bottom)
				(hide yes)
			)
		)
		(pin "2"
		)
		(pin "1"
		)
		(instances
			(project "com-express-7-baseboard"
				(path ""
					(reference "R54")
					(unit 1)
				)
			)
		)
	)
	(symbol
		(lib_id "antmicroResistors0402:R_0R_0402")
		(at 256.54 167.64 180)
		(unit 1)
		(exclude_from_sim no)
		(in_bom yes)
		(on_board yes)
		(dnp no)
		(property "Reference" "R59"
			(at 259.08 166.37 0)
			(effects
				(font
					(size 1.27 1.27)
					(thickness 0.15)
				)
			)
		)
		(property "Value" "R_0R_0402"
			(at 236.22 154.94 0)
			(effects
				(font
					(size 1.27 1.27)
					(thickness 0.15)
				)
				(justify left bottom)
				(hide yes)
			)
		)
		(property "Footprint" "antmicro-footprints:R_0402_1005Metric"
			(at 236.22 152.4 0)
			(effects
				(font
					(size 1.27 1.27)
					(thickness 0.15)
				)
				(justify left bottom)
				(hide yes)
			)
		)
		(property "Datasheet" "https://industrial.panasonic.com/cdbs/www-data/pdf/RDA0000/AOA0000C301.pdf"
			(at 236.22 149.86 0)
			(effects
				(font
					(size 1.27 1.27)
					(thickness 0.15)
				)
				(justify left bottom)
				(hide yes)
			)
		)
		(property "Description" ""
			(at 256.54 167.64 0)
			(effects
				(font
					(size 1.27 1.27)
				)
				(hide yes)
			)
		)
		(property "MPN" "ERJ2GE0R00X"
			(at 236.22 147.32 0)
			(effects
				(font
					(size 1.27 1.27)
					(thickness 0.15)
				)
				(justify left bottom)
				(hide yes)
			)
		)
		(property "Manufacturer" "Panasonic"
			(at 236.22 144.78 0)
			(effects
				(font
					(size 1.27 1.27)
					(thickness 0.15)
				)
				(justify left bottom)
				(hide yes)
			)
		)
		(property "License" "Apache-2.0"
			(at 236.22 142.24 0)
			(effects
				(font
					(size 1.27 1.27)
					(thickness 0.15)
				)
				(justify left bottom)
				(hide yes)
			)
		)
		(property "Author" "Antmicro"
			(at 236.22 139.7 0)
			(effects
				(font
					(size 1.27 1.27)
					(thickness 0.15)
				)
				(justify left bottom)
				(hide yes)
			)
		)
		(property "Val" "0R"
			(at 250.19 166.37 0)
			(effects
				(font
					(size 1.27 1.27)
					(thickness 0.15)
				)
			)
		)
		(property "Tolerance" "~"
			(at 236.22 157.48 0)
			(effects
				(font
					(size 1.27 1.27)
				)
				(justify left bottom)
				(hide yes)
			)
		)
		(property "Current" "1A"
			(at 236.22 137.16 0)
			(effects
				(font
					(size 1.27 1.27)
					(thickness 0.15)
				)
				(justify left bottom)
				(hide yes)
			)
		)
		(property "Public" "False"
			(at 236.22 137.16 0)
			(effects
				(font
					(size 1.27 1.27)
				)
				(justify left bottom)
				(hide yes)
			)
		)
		(pin "2"
		)
		(pin "1"
		)
		(instances
			(project "com-express-7-baseboard"
				(path ""
					(reference "R59")
					(unit 1)
				)
			)
		)
	)
	(symbol
		(lib_id "antmicroCapacitors0402:C_100n_0402")
		(at 330.2 104.14 90)
		(mirror x)
		(unit 1)
		(exclude_from_sim no)
		(in_bom yes)
		(on_board yes)
		(dnp no)
		(property "Reference" "C210"
			(at 336.55 105.41 90)
			(effects
				(font
					(size 1.27 1.27)
					(thickness 0.15)
				)
				(justify left)
			)
		)
		(property "Value" "C_100n_0402"
			(at 340.36 124.46 0)
			(effects
				(font
					(size 1.27 1.27)
					(thickness 0.15)
				)
				(justify left bottom)
				(hide yes)
			)
		)
		(property "Footprint" "antmicro-footprints:C_0402_1005Metric"
			(at 342.9 124.46 0)
			(effects
				(font
					(size 1.27 1.27)
					(thickness 0.15)
				)
				(justify left bottom)
				(hide yes)
			)
		)
		(property "Datasheet" "https://www.murata.com/products/productdetail?partno=GRM155R61H104KE14%23"
			(at 345.44 124.46 0)
			(effects
				(font
					(size 1.27 1.27)
					(thickness 0.15)
				)
				(justify left bottom)
				(hide yes)
			)
		)
		(property "Description" ""
			(at 330.2 104.14 0)
			(effects
				(font
					(size 1.27 1.27)
				)
				(hide yes)
			)
		)
		(property "MPN" "GRM155R61H104KE14D"
			(at 347.98 124.46 0)
			(effects
				(font
					(size 1.27 1.27)
					(thickness 0.15)
				)
				(justify left bottom)
				(hide yes)
			)
		)
		(property "Manufacturer" "Murata"
			(at 350.52 124.46 0)
			(effects
				(font
					(size 1.27 1.27)
					(thickness 0.15)
				)
				(justify left bottom)
				(hide yes)
			)
		)
		(property "License" "Apache-2.0"
			(at 353.06 124.46 0)
			(effects
				(font
					(size 1.27 1.27)
					(thickness 0.15)
				)
				(justify left bottom)
				(hide yes)
			)
		)
		(property "Author" "Antmicro"
			(at 355.6 124.46 0)
			(effects
				(font
					(size 1.27 1.27)
					(thickness 0.15)
				)
				(justify left bottom)
				(hide yes)
			)
		)
		(property "Val" "100n"
			(at 336.55 107.95 90)
			(effects
				(font
					(size 1.27 1.27)
					(thickness 0.15)
				)
				(justify left)
			)
		)
		(property "Voltage" "50V"
			(at 358.14 124.46 0)
			(effects
				(font
					(size 1.27 1.27)
				)
				(justify left bottom)
				(hide yes)
			)
		)
		(property "Dielectric" "X5R"
			(at 360.68 124.46 0)
			(effects
				(font
					(size 1.27 1.27)
				)
				(justify left bottom)
				(hide yes)
			)
		)
		(property "Public" "False"
			(at 363.22 124.46 0)
			(effects
				(font
					(size 1.27 1.27)
				)
				(justify left bottom)
				(hide yes)
			)
		)
		(pin "1"
		)
		(pin "2"
		)
		(instances
			(project "com-express-7-baseboard"
				(path ""
					(reference "C210")
					(unit 1)
				)
			)
		)
	)
	(symbol
		(lib_id "antmicropower:GND")
		(at 232.41 125.73 0)
		(mirror y)
		(unit 1)
		(exclude_from_sim no)
		(in_bom yes)
		(on_board yes)
		(dnp no)
		(property "Reference" "#PWR043"
			(at 223.52 128.27 0)
			(effects
				(font
					(size 1.27 1.27)
					(thickness 0.15)
				)
				(justify left bottom)
				(hide yes)
			)
		)
		(property "Value" "GND"
			(at 232.41 129.54 0)
			(effects
				(font
					(size 1.27 1.27)
					(thickness 0.15)
				)
			)
		)
		(property "Footprint" ""
			(at 223.52 133.35 0)
			(effects
				(font
					(size 1.27 1.27)
					(thickness 0.15)
				)
				(justify left bottom)
				(hide yes)
			)
		)
		(property "Datasheet" ""
			(at 223.52 138.43 0)
			(effects
				(font
					(size 1.27 1.27)
					(thickness 0.15)
				)
				(justify left bottom)
				(hide yes)
			)
		)
		(property "Description" ""
			(at 232.41 125.73 0)
			(effects
				(font
					(size 1.27 1.27)
				)
				(hide yes)
			)
		)
		(property "Author" "Antmicro"
			(at 223.52 133.35 0)
			(effects
				(font
					(size 1.27 1.27)
					(thickness 0.15)
				)
				(justify left bottom)
				(hide yes)
			)
		)
		(property "License" "Apache-2.0"
			(at 223.52 135.89 0)
			(effects
				(font
					(size 1.27 1.27)
					(thickness 0.15)
				)
				(justify left bottom)
				(hide yes)
			)
		)
		(pin "1"
		)
		(instances
			(project "com-express-7-baseboard"
				(path ""
					(reference "#PWR043")
					(unit 1)
				)
			)
		)
	)
	(symbol
		(lib_id "antmicroTestPoints:TP_0.75mm_SMD")
		(at 203.2 246.38 0)
		(unit 1)
		(exclude_from_sim no)
		(in_bom no)
		(on_board yes)
		(dnp no)
		(property "Reference" "TP2"
			(at 207.01 246.38 0)
			(effects
				(font
					(size 1.27 1.27)
					(thickness 0.15)
				)
				(justify left)
			)
		)
		(property "Value" "TP_0.75mm_SMD"
			(at 213.995 250.19 0)
			(effects
				(font
					(size 1.27 1.27)
					(thickness 0.15)
				)
				(justify left bottom)
				(hide yes)
			)
		)
		(property "Footprint" "antmicro-footprints:TP_SMD_0.75mm"
			(at 213.995 252.73 0)
			(effects
				(font
					(size 1.27 1.27)
					(thickness 0.15)
				)
				(justify left bottom)
				(hide yes)
			)
		)
		(property "Datasheet" ""
			(at 220.98 259.08 0)
			(effects
				(font
					(size 1.27 1.27)
					(thickness 0.15)
				)
				(justify left bottom)
				(hide yes)
			)
		)
		(property "Description" ""
			(at 203.2 246.38 0)
			(effects
				(font
					(size 1.27 1.27)
				)
				(hide yes)
			)
		)
		(property "MPN" ""
			(at 213.995 257.81 0)
			(effects
				(font
					(size 1.27 1.27)
					(thickness 0.15)
				)
				(justify left bottom)
				(hide yes)
			)
		)
		(property "Manufacturer" ""
			(at 213.995 252.73 0)
			(effects
				(font
					(size 1.27 1.27)
					(thickness 0.15)
				)
				(justify left bottom)
				(hide yes)
			)
		)
		(property "Author" "Antmicro"
			(at 213.995 255.27 0)
			(effects
				(font
					(size 1.27 1.27)
					(thickness 0.15)
				)
				(justify left bottom)
				(hide yes)
			)
		)
		(property "License" "Apache-2.0"
			(at 213.995 257.81 0)
			(effects
				(font
					(size 1.27 1.27)
					(thickness 0.15)
				)
				(justify left bottom)
				(hide yes)
			)
		)
		(property "Public" "False"
			(at 213.36 260.35 0)
			(effects
				(font
					(size 1.27 1.27)
				)
				(justify left bottom)
				(hide yes)
			)
		)
		(pin "1"
		)
		(instances
			(project "com-express-7-baseboard"
				(path ""
					(reference "TP2")
					(unit 1)
				)
			)
		)
	)
	(symbol
		(lib_id "antmicroCapacitors0402:C_100n_0402")
		(at 356.87 104.14 90)
		(mirror x)
		(unit 1)
		(exclude_from_sim no)
		(in_bom yes)
		(on_board yes)
		(dnp no)
		(property "Reference" "C213"
			(at 363.22 105.41 90)
			(effects
				(font
					(size 1.27 1.27)
					(thickness 0.15)
				)
				(justify left)
			)
		)
		(property "Value" "C_100n_0402"
			(at 367.03 124.46 0)
			(effects
				(font
					(size 1.27 1.27)
					(thickness 0.15)
				)
				(justify left bottom)
				(hide yes)
			)
		)
		(property "Footprint" "antmicro-footprints:C_0402_1005Metric"
			(at 369.57 124.46 0)
			(effects
				(font
					(size 1.27 1.27)
					(thickness 0.15)
				)
				(justify left bottom)
				(hide yes)
			)
		)
		(property "Datasheet" "https://www.murata.com/products/productdetail?partno=GRM155R61H104KE14%23"
			(at 372.11 124.46 0)
			(effects
				(font
					(size 1.27 1.27)
					(thickness 0.15)
				)
				(justify left bottom)
				(hide yes)
			)
		)
		(property "Description" ""
			(at 356.87 104.14 0)
			(effects
				(font
					(size 1.27 1.27)
				)
				(hide yes)
			)
		)
		(property "MPN" "GRM155R61H104KE14D"
			(at 374.65 124.46 0)
			(effects
				(font
					(size 1.27 1.27)
					(thickness 0.15)
				)
				(justify left bottom)
				(hide yes)
			)
		)
		(property "Manufacturer" "Murata"
			(at 377.19 124.46 0)
			(effects
				(font
					(size 1.27 1.27)
					(thickness 0.15)
				)
				(justify left bottom)
				(hide yes)
			)
		)
		(property "License" "Apache-2.0"
			(at 379.73 124.46 0)
			(effects
				(font
					(size 1.27 1.27)
					(thickness 0.15)
				)
				(justify left bottom)
				(hide yes)
			)
		)
		(property "Author" "Antmicro"
			(at 382.27 124.46 0)
			(effects
				(font
					(size 1.27 1.27)
					(thickness 0.15)
				)
				(justify left bottom)
				(hide yes)
			)
		)
		(property "Val" "100n"
			(at 363.22 107.95 90)
			(effects
				(font
					(size 1.27 1.27)
					(thickness 0.15)
				)
				(justify left)
			)
		)
		(property "Voltage" "50V"
			(at 384.81 124.46 0)
			(effects
				(font
					(size 1.27 1.27)
				)
				(justify left bottom)
				(hide yes)
			)
		)
		(property "Dielectric" "X5R"
			(at 387.35 124.46 0)
			(effects
				(font
					(size 1.27 1.27)
				)
				(justify left bottom)
				(hide yes)
			)
		)
		(property "Public" "False"
			(at 389.89 124.46 0)
			(effects
				(font
					(size 1.27 1.27)
				)
				(justify left bottom)
				(hide yes)
			)
		)
		(pin "1"
		)
		(pin "2"
		)
		(instances
			(project "com-express-7-baseboard"
				(path ""
					(reference "C213")
					(unit 1)
				)
			)
		)
	)
	(symbol
		(lib_id "antmicroResistors0402:R_220R_0402")
		(at 321.31 161.29 90)
		(unit 1)
		(exclude_from_sim no)
		(in_bom yes)
		(on_board yes)
		(dnp no)
		(property "Reference" "R62"
			(at 322.58 157.48 90)
			(effects
				(font
					(size 1.27 1.27)
					(thickness 0.15)
				)
				(justify right)
			)
		)
		(property "Value" "R_220R_0402"
			(at 334.01 140.97 0)
			(effects
				(font
					(size 1.27 1.27)
					(thickness 0.15)
				)
				(justify left bottom)
				(hide yes)
			)
		)
		(property "Footprint" "antmicro-footprints:R_0402_1005Metric"
			(at 336.55 140.97 0)
			(effects
				(font
					(size 1.27 1.27)
					(thickness 0.15)
				)
				(justify left bottom)
				(hide yes)
			)
		)
		(property "Datasheet" "https://www.bourns.com/docs/product-datasheets/cr.pdf"
			(at 339.09 140.97 0)
			(effects
				(font
					(size 1.27 1.27)
					(thickness 0.15)
				)
				(justify left bottom)
				(hide yes)
			)
		)
		(property "Description" ""
			(at 321.31 161.29 0)
			(effects
				(font
					(size 1.27 1.27)
				)
				(hide yes)
			)
		)
		(property "MPN" "CR0402-FX-2200GLF"
			(at 341.63 140.97 0)
			(effects
				(font
					(size 1.27 1.27)
					(thickness 0.15)
				)
				(justify left bottom)
				(hide yes)
			)
		)
		(property "Manufacturer" "Bourns"
			(at 344.17 140.97 0)
			(effects
				(font
					(size 1.27 1.27)
					(thickness 0.15)
				)
				(justify left bottom)
				(hide yes)
			)
		)
		(property "License" "Apache-2.0"
			(at 346.71 140.97 0)
			(effects
				(font
					(size 1.27 1.27)
					(thickness 0.15)
				)
				(justify left bottom)
				(hide yes)
			)
		)
		(property "Author" "Antmicro"
			(at 349.25 140.97 0)
			(effects
				(font
					(size 1.27 1.27)
					(thickness 0.15)
				)
				(justify left bottom)
				(hide yes)
			)
		)
		(property "Val" "220R"
			(at 322.58 160.02 90)
			(effects
				(font
					(size 1.27 1.27)
					(thickness 0.15)
				)
				(justify right)
			)
		)
		(property "Tolerance" "1%"
			(at 331.47 140.97 0)
			(effects
				(font
					(size 1.27 1.27)
				)
				(justify left bottom)
				(hide yes)
			)
		)
		(property "Public" "False"
			(at 351.79 140.97 0)
			(effects
				(font
					(size 1.27 1.27)
				)
				(justify left bottom)
				(hide yes)
			)
		)
		(pin "2"
		)
		(pin "1"
		)
		(instances
			(project "com-express-7-baseboard"
				(path ""
					(reference "R62")
					(unit 1)
				)
			)
		)
	)
	(symbol
		(lib_id "antmicroCapacitors0402:C_100n_0402")
		(at 241.3 41.91 90)
		(unit 1)
		(exclude_from_sim no)
		(in_bom yes)
		(on_board yes)
		(dnp no)
		(fields_autoplaced yes)
		(property "Reference" "C24"
			(at 243.84 38.0936 90)
			(effects
				(font
					(size 1.27 1.27)
					(thickness 0.15)
				)
				(justify right)
			)
		)
		(property "Value" "C_100n_0402"
			(at 251.46 21.59 0)
			(effects
				(font
					(size 1.27 1.27)
					(thickness 0.15)
				)
				(justify left bottom)
				(hide yes)
			)
		)
		(property "Footprint" "antmicro-footprints:C_0402_1005Metric"
			(at 254 21.59 0)
			(effects
				(font
					(size 1.27 1.27)
					(thickness 0.15)
				)
				(justify left bottom)
				(hide yes)
			)
		)
		(property "Datasheet" "https://www.murata.com/products/productdetail?partno=GRM155R61H104KE14%23"
			(at 256.54 21.59 0)
			(effects
				(font
					(size 1.27 1.27)
					(thickness 0.15)
				)
				(justify left bottom)
				(hide yes)
			)
		)
		(property "Description" ""
			(at 241.3 41.91 0)
			(effects
				(font
					(size 1.27 1.27)
				)
				(hide yes)
			)
		)
		(property "MPN" "GRM155R61H104KE14D"
			(at 259.08 21.59 0)
			(effects
				(font
					(size 1.27 1.27)
					(thickness 0.15)
				)
				(justify left bottom)
				(hide yes)
			)
		)
		(property "Manufacturer" "Murata"
			(at 261.62 21.59 0)
			(effects
				(font
					(size 1.27 1.27)
					(thickness 0.15)
				)
				(justify left bottom)
				(hide yes)
			)
		)
		(property "License" "Apache-2.0"
			(at 264.16 21.59 0)
			(effects
				(font
					(size 1.27 1.27)
					(thickness 0.15)
				)
				(justify left bottom)
				(hide yes)
			)
		)
		(property "Author" "Antmicro"
			(at 266.7 21.59 0)
			(effects
				(font
					(size 1.27 1.27)
					(thickness 0.15)
				)
				(justify left bottom)
				(hide yes)
			)
		)
		(property "Val" "100n"
			(at 243.84 40.6336 90)
			(effects
				(font
					(size 1.27 1.27)
					(thickness 0.15)
				)
				(justify right)
			)
		)
		(property "Voltage" "50V"
			(at 269.24 21.59 0)
			(effects
				(font
					(size 1.27 1.27)
				)
				(justify left bottom)
				(hide yes)
			)
		)
		(property "Dielectric" "X5R"
			(at 271.78 21.59 0)
			(effects
				(font
					(size 1.27 1.27)
				)
				(justify left bottom)
				(hide yes)
			)
		)
		(property "Public" "False"
			(at 274.32 21.59 0)
			(effects
				(font
					(size 1.27 1.27)
				)
				(justify left bottom)
				(hide yes)
			)
		)
		(pin "2"
		)
		(pin "1"
		)
		(instances
			(project "com-express-7-baseboard"
				(path ""
					(reference "C24")
					(unit 1)
				)
			)
		)
	)
	(symbol
		(lib_id "antmicropower:GND")
		(at 250.19 125.73 0)
		(mirror y)
		(unit 1)
		(exclude_from_sim no)
		(in_bom yes)
		(on_board yes)
		(dnp no)
		(property "Reference" "#PWR049"
			(at 241.3 128.27 0)
			(effects
				(font
					(size 1.27 1.27)
					(thickness 0.15)
				)
				(justify left bottom)
				(hide yes)
			)
		)
		(property "Value" "GND"
			(at 250.19 129.54 0)
			(effects
				(font
					(size 1.27 1.27)
					(thickness 0.15)
				)
			)
		)
		(property "Footprint" ""
			(at 241.3 133.35 0)
			(effects
				(font
					(size 1.27 1.27)
					(thickness 0.15)
				)
				(justify left bottom)
				(hide yes)
			)
		)
		(property "Datasheet" ""
			(at 241.3 138.43 0)
			(effects
				(font
					(size 1.27 1.27)
					(thickness 0.15)
				)
				(justify left bottom)
				(hide yes)
			)
		)
		(property "Description" ""
			(at 250.19 125.73 0)
			(effects
				(font
					(size 1.27 1.27)
				)
				(hide yes)
			)
		)
		(property "Author" "Antmicro"
			(at 241.3 133.35 0)
			(effects
				(font
					(size 1.27 1.27)
					(thickness 0.15)
				)
				(justify left bottom)
				(hide yes)
			)
		)
		(property "License" "Apache-2.0"
			(at 241.3 135.89 0)
			(effects
				(font
					(size 1.27 1.27)
					(thickness 0.15)
				)
				(justify left bottom)
				(hide yes)
			)
		)
		(pin "1"
		)
		(instances
			(project "com-express-7-baseboard"
				(path ""
					(reference "#PWR049")
					(unit 1)
				)
			)
		)
	)
	(symbol
		(lib_id "antmicroTestPoints:TP_0.75mm_SMD")
		(at 241.3 162.56 180)
		(unit 1)
		(exclude_from_sim no)
		(in_bom no)
		(on_board yes)
		(dnp no)
		(property "Reference" "TP6"
			(at 232.41 162.56 0)
			(effects
				(font
					(size 1.27 1.27)
					(thickness 0.15)
				)
			)
		)
		(property "Value" "TP_0.75mm_SMD"
			(at 230.505 158.75 0)
			(effects
				(font
					(size 1.27 1.27)
					(thickness 0.15)
				)
				(justify left bottom)
				(hide yes)
			)
		)
		(property "Footprint" "antmicro-footprints:TP_SMD_0.75mm"
			(at 230.505 156.21 0)
			(effects
				(font
					(size 1.27 1.27)
					(thickness 0.15)
				)
				(justify left bottom)
				(hide yes)
			)
		)
		(property "Datasheet" ""
			(at 223.52 149.86 0)
			(effects
				(font
					(size 1.27 1.27)
					(thickness 0.15)
				)
				(justify left bottom)
				(hide yes)
			)
		)
		(property "Description" ""
			(at 241.3 162.56 0)
			(effects
				(font
					(size 1.27 1.27)
				)
				(hide yes)
			)
		)
		(property "MPN" ""
			(at 230.505 151.13 0)
			(effects
				(font
					(size 1.27 1.27)
					(thickness 0.15)
				)
				(justify left bottom)
				(hide yes)
			)
		)
		(property "Manufacturer" ""
			(at 230.505 156.21 0)
			(effects
				(font
					(size 1.27 1.27)
					(thickness 0.15)
				)
				(justify left bottom)
				(hide yes)
			)
		)
		(property "Author" "Antmicro"
			(at 230.505 153.67 0)
			(effects
				(font
					(size 1.27 1.27)
					(thickness 0.15)
				)
				(justify left bottom)
				(hide yes)
			)
		)
		(property "License" "Apache-2.0"
			(at 230.505 151.13 0)
			(effects
				(font
					(size 1.27 1.27)
					(thickness 0.15)
				)
				(justify left bottom)
				(hide yes)
			)
		)
		(property "Public" "False"
			(at 231.14 148.59 0)
			(effects
				(font
					(size 1.27 1.27)
				)
				(justify left bottom)
				(hide yes)
			)
		)
		(pin "1"
		)
		(instances
			(project "com-express-7-baseboard"
				(path ""
					(reference "TP6")
					(unit 1)
				)
			)
		)
	)
	(symbol
		(lib_id "antmicropower:GND")
		(at 243.84 85.09 0)
		(unit 1)
		(exclude_from_sim no)
		(in_bom yes)
		(on_board yes)
		(dnp no)
		(property "Reference" "#PWR046"
			(at 252.73 87.63 0)
			(effects
				(font
					(size 1.27 1.27)
					(thickness 0.15)
				)
				(justify left bottom)
				(hide yes)
			)
		)
		(property "Value" "GND"
			(at 240.03 86.36 0)
			(effects
				(font
					(size 1.27 1.27)
					(thickness 0.15)
				)
			)
		)
		(property "Footprint" ""
			(at 252.73 92.71 0)
			(effects
				(font
					(size 1.27 1.27)
					(thickness 0.15)
				)
				(justify left bottom)
				(hide yes)
			)
		)
		(property "Datasheet" ""
			(at 252.73 97.79 0)
			(effects
				(font
					(size 1.27 1.27)
					(thickness 0.15)
				)
				(justify left bottom)
				(hide yes)
			)
		)
		(property "Description" ""
			(at 243.84 85.09 0)
			(effects
				(font
					(size 1.27 1.27)
				)
				(hide yes)
			)
		)
		(property "Author" "Antmicro"
			(at 252.73 92.71 0)
			(effects
				(font
					(size 1.27 1.27)
					(thickness 0.15)
				)
				(justify left bottom)
				(hide yes)
			)
		)
		(property "License" "Apache-2.0"
			(at 252.73 95.25 0)
			(effects
				(font
					(size 1.27 1.27)
					(thickness 0.15)
				)
				(justify left bottom)
				(hide yes)
			)
		)
		(pin "1"
		)
		(instances
			(project "com-express-7-baseboard"
				(path ""
					(reference "#PWR046")
					(unit 1)
				)
			)
		)
	)
	(symbol
		(lib_id "antmicroResistors0402:R_0R_0402")
		(at 256.54 83.82 180)
		(unit 1)
		(exclude_from_sim no)
		(in_bom yes)
		(on_board yes)
		(dnp no)
		(property "Reference" "R57"
			(at 259.08 82.55 0)
			(effects
				(font
					(size 1.27 1.27)
					(thickness 0.15)
				)
			)
		)
		(property "Value" "R_0R_0402"
			(at 236.22 71.12 0)
			(effects
				(font
					(size 1.27 1.27)
					(thickness 0.15)
				)
				(justify left bottom)
				(hide yes)
			)
		)
		(property "Footprint" "antmicro-footprints:R_0402_1005Metric"
			(at 236.22 68.58 0)
			(effects
				(font
					(size 1.27 1.27)
					(thickness 0.15)
				)
				(justify left bottom)
				(hide yes)
			)
		)
		(property "Datasheet" "https://industrial.panasonic.com/cdbs/www-data/pdf/RDA0000/AOA0000C301.pdf"
			(at 236.22 66.04 0)
			(effects
				(font
					(size 1.27 1.27)
					(thickness 0.15)
				)
				(justify left bottom)
				(hide yes)
			)
		)
		(property "Description" ""
			(at 256.54 83.82 0)
			(effects
				(font
					(size 1.27 1.27)
				)
				(hide yes)
			)
		)
		(property "MPN" "ERJ2GE0R00X"
			(at 236.22 63.5 0)
			(effects
				(font
					(size 1.27 1.27)
					(thickness 0.15)
				)
				(justify left bottom)
				(hide yes)
			)
		)
		(property "Manufacturer" "Panasonic"
			(at 236.22 60.96 0)
			(effects
				(font
					(size 1.27 1.27)
					(thickness 0.15)
				)
				(justify left bottom)
				(hide yes)
			)
		)
		(property "License" "Apache-2.0"
			(at 236.22 58.42 0)
			(effects
				(font
					(size 1.27 1.27)
					(thickness 0.15)
				)
				(justify left bottom)
				(hide yes)
			)
		)
		(property "Author" "Antmicro"
			(at 236.22 55.88 0)
			(effects
				(font
					(size 1.27 1.27)
					(thickness 0.15)
				)
				(justify left bottom)
				(hide yes)
			)
		)
		(property "Val" "0R"
			(at 250.19 82.55 0)
			(effects
				(font
					(size 1.27 1.27)
					(thickness 0.15)
				)
			)
		)
		(property "Tolerance" "~"
			(at 236.22 73.66 0)
			(effects
				(font
					(size 1.27 1.27)
				)
				(justify left bottom)
				(hide yes)
			)
		)
		(property "Current" "1A"
			(at 236.22 53.34 0)
			(effects
				(font
					(size 1.27 1.27)
					(thickness 0.15)
				)
				(justify left bottom)
				(hide yes)
			)
		)
		(property "Public" "False"
			(at 236.22 53.34 0)
			(effects
				(font
					(size 1.27 1.27)
				)
				(justify left bottom)
				(hide yes)
			)
		)
		(pin "2"
		)
		(pin "1"
		)
		(instances
			(project "com-express-7-baseboard"
				(path ""
					(reference "R57")
					(unit 1)
				)
			)
		)
	)
	(symbol
		(lib_id "antmicroResistors0402:R_0R_0402")
		(at 256.54 170.18 180)
		(unit 1)
		(exclude_from_sim no)
		(in_bom yes)
		(on_board yes)
		(dnp no)
		(property "Reference" "R60"
			(at 259.08 168.91 0)
			(effects
				(font
					(size 1.27 1.27)
					(thickness 0.15)
				)
			)
		)
		(property "Value" "R_0R_0402"
			(at 236.22 157.48 0)
			(effects
				(font
					(size 1.27 1.27)
					(thickness 0.15)
				)
				(justify left bottom)
				(hide yes)
			)
		)
		(property "Footprint" "antmicro-footprints:R_0402_1005Metric"
			(at 236.22 154.94 0)
			(effects
				(font
					(size 1.27 1.27)
					(thickness 0.15)
				)
				(justify left bottom)
				(hide yes)
			)
		)
		(property "Datasheet" "https://industrial.panasonic.com/cdbs/www-data/pdf/RDA0000/AOA0000C301.pdf"
			(at 236.22 152.4 0)
			(effects
				(font
					(size 1.27 1.27)
					(thickness 0.15)
				)
				(justify left bottom)
				(hide yes)
			)
		)
		(property "Description" ""
			(at 256.54 170.18 0)
			(effects
				(font
					(size 1.27 1.27)
				)
				(hide yes)
			)
		)
		(property "MPN" "ERJ2GE0R00X"
			(at 236.22 149.86 0)
			(effects
				(font
					(size 1.27 1.27)
					(thickness 0.15)
				)
				(justify left bottom)
				(hide yes)
			)
		)
		(property "Manufacturer" "Panasonic"
			(at 236.22 147.32 0)
			(effects
				(font
					(size 1.27 1.27)
					(thickness 0.15)
				)
				(justify left bottom)
				(hide yes)
			)
		)
		(property "License" "Apache-2.0"
			(at 236.22 144.78 0)
			(effects
				(font
					(size 1.27 1.27)
					(thickness 0.15)
				)
				(justify left bottom)
				(hide yes)
			)
		)
		(property "Author" "Antmicro"
			(at 236.22 142.24 0)
			(effects
				(font
					(size 1.27 1.27)
					(thickness 0.15)
				)
				(justify left bottom)
				(hide yes)
			)
		)
		(property "Val" "0R"
			(at 250.19 168.91 0)
			(effects
				(font
					(size 1.27 1.27)
					(thickness 0.15)
				)
			)
		)
		(property "Tolerance" "~"
			(at 236.22 160.02 0)
			(effects
				(font
					(size 1.27 1.27)
				)
				(justify left bottom)
				(hide yes)
			)
		)
		(property "Current" "1A"
			(at 236.22 139.7 0)
			(effects
				(font
					(size 1.27 1.27)
					(thickness 0.15)
				)
				(justify left bottom)
				(hide yes)
			)
		)
		(property "Public" "False"
			(at 236.22 139.7 0)
			(effects
				(font
					(size 1.27 1.27)
				)
				(justify left bottom)
				(hide yes)
			)
		)
		(pin "2"
		)
		(pin "1"
		)
		(instances
			(project "com-express-7-baseboard"
				(path ""
					(reference "R60")
					(unit 1)
				)
			)
		)
	)
	(symbol
		(lib_id "antmicroResistors0402:R_0R_0402")
		(at 219.71 228.6 0)
		(unit 1)
		(exclude_from_sim no)
		(in_bom yes)
		(on_board yes)
		(dnp no)
		(property "Reference" "R43"
			(at 217.17 227.33 0)
			(effects
				(font
					(size 1.27 1.27)
					(thickness 0.15)
				)
			)
		)
		(property "Value" "R_0R_0402"
			(at 240.03 241.3 0)
			(effects
				(font
					(size 1.27 1.27)
					(thickness 0.15)
				)
				(justify left bottom)
				(hide yes)
			)
		)
		(property "Footprint" "antmicro-footprints:R_0402_1005Metric"
			(at 240.03 243.84 0)
			(effects
				(font
					(size 1.27 1.27)
					(thickness 0.15)
				)
				(justify left bottom)
				(hide yes)
			)
		)
		(property "Datasheet" "https://industrial.panasonic.com/cdbs/www-data/pdf/RDA0000/AOA0000C301.pdf"
			(at 240.03 246.38 0)
			(effects
				(font
					(size 1.27 1.27)
					(thickness 0.15)
				)
				(justify left bottom)
				(hide yes)
			)
		)
		(property "Description" ""
			(at 219.71 228.6 0)
			(effects
				(font
					(size 1.27 1.27)
				)
				(hide yes)
			)
		)
		(property "MPN" "ERJ2GE0R00X"
			(at 240.03 248.92 0)
			(effects
				(font
					(size 1.27 1.27)
					(thickness 0.15)
				)
				(justify left bottom)
				(hide yes)
			)
		)
		(property "Manufacturer" "Panasonic"
			(at 240.03 251.46 0)
			(effects
				(font
					(size 1.27 1.27)
					(thickness 0.15)
				)
				(justify left bottom)
				(hide yes)
			)
		)
		(property "License" "Apache-2.0"
			(at 240.03 254 0)
			(effects
				(font
					(size 1.27 1.27)
					(thickness 0.15)
				)
				(justify left bottom)
				(hide yes)
			)
		)
		(property "Author" "Antmicro"
			(at 240.03 256.54 0)
			(effects
				(font
					(size 1.27 1.27)
					(thickness 0.15)
				)
				(justify left bottom)
				(hide yes)
			)
		)
		(property "Val" "0R"
			(at 226.06 227.33 0)
			(effects
				(font
					(size 1.27 1.27)
					(thickness 0.15)
				)
			)
		)
		(property "Tolerance" "~"
			(at 240.03 238.76 0)
			(effects
				(font
					(size 1.27 1.27)
				)
				(justify left bottom)
				(hide yes)
			)
		)
		(property "Current" "1A"
			(at 240.03 259.08 0)
			(effects
				(font
					(size 1.27 1.27)
					(thickness 0.15)
				)
				(justify left bottom)
				(hide yes)
			)
		)
		(property "Public" "False"
			(at 240.03 259.08 0)
			(effects
				(font
					(size 1.27 1.27)
				)
				(justify left bottom)
				(hide yes)
			)
		)
		(pin "2"
		)
		(pin "1"
		)
		(instances
			(project "com-express-7-baseboard"
				(path ""
					(reference "R43")
					(unit 1)
				)
			)
		)
	)
	(symbol
		(lib_id "antmicroCapacitors0402:C_100n_0402")
		(at 168.91 224.79 270)
		(mirror x)
		(unit 1)
		(exclude_from_sim no)
		(in_bom yes)
		(on_board yes)
		(dnp no)
		(property "Reference" "C21"
			(at 166.37 220.9736 90)
			(effects
				(font
					(size 1.27 1.27)
					(thickness 0.15)
				)
				(justify right)
			)
		)
		(property "Value" "C_100n_0402"
			(at 158.75 204.47 0)
			(effects
				(font
					(size 1.27 1.27)
					(thickness 0.15)
				)
				(justify left bottom)
				(hide yes)
			)
		)
		(property "Footprint" "antmicro-footprints:C_0402_1005Metric"
			(at 156.21 204.47 0)
			(effects
				(font
					(size 1.27 1.27)
					(thickness 0.15)
				)
				(justify left bottom)
				(hide yes)
			)
		)
		(property "Datasheet" "https://www.murata.com/products/productdetail?partno=GRM155R61H104KE14%23"
			(at 153.67 204.47 0)
			(effects
				(font
					(size 1.27 1.27)
					(thickness 0.15)
				)
				(justify left bottom)
				(hide yes)
			)
		)
		(property "Description" ""
			(at 168.91 224.79 0)
			(effects
				(font
					(size 1.27 1.27)
				)
				(hide yes)
			)
		)
		(property "MPN" "GRM155R61H104KE14D"
			(at 151.13 204.47 0)
			(effects
				(font
					(size 1.27 1.27)
					(thickness 0.15)
				)
				(justify left bottom)
				(hide yes)
			)
		)
		(property "Manufacturer" "Murata"
			(at 148.59 204.47 0)
			(effects
				(font
					(size 1.27 1.27)
					(thickness 0.15)
				)
				(justify left bottom)
				(hide yes)
			)
		)
		(property "License" "Apache-2.0"
			(at 146.05 204.47 0)
			(effects
				(font
					(size 1.27 1.27)
					(thickness 0.15)
				)
				(justify left bottom)
				(hide yes)
			)
		)
		(property "Author" "Antmicro"
			(at 143.51 204.47 0)
			(effects
				(font
					(size 1.27 1.27)
					(thickness 0.15)
				)
				(justify left bottom)
				(hide yes)
			)
		)
		(property "Val" "100n"
			(at 166.37 223.5136 90)
			(effects
				(font
					(size 1.27 1.27)
					(thickness 0.15)
				)
				(justify right)
			)
		)
		(property "Voltage" "50V"
			(at 140.97 204.47 0)
			(effects
				(font
					(size 1.27 1.27)
				)
				(justify left bottom)
				(hide yes)
			)
		)
		(property "Dielectric" "X5R"
			(at 138.43 204.47 0)
			(effects
				(font
					(size 1.27 1.27)
				)
				(justify left bottom)
				(hide yes)
			)
		)
		(property "Public" "False"
			(at 135.89 204.47 0)
			(effects
				(font
					(size 1.27 1.27)
				)
				(justify left bottom)
				(hide yes)
			)
		)
		(pin "2"
		)
		(pin "1"
		)
		(instances
			(project "com-express-7-baseboard"
				(path ""
					(reference "C21")
					(unit 1)
				)
			)
		)
	)
	(symbol
		(lib_id "antmicroCapacitors0402:C_100n_0402")
		(at 303.53 104.14 90)
		(mirror x)
		(unit 1)
		(exclude_from_sim no)
		(in_bom yes)
		(on_board yes)
		(dnp no)
		(property "Reference" "C28"
			(at 309.88 105.41 90)
			(effects
				(font
					(size 1.27 1.27)
					(thickness 0.15)
				)
				(justify left)
			)
		)
		(property "Value" "C_100n_0402"
			(at 313.69 124.46 0)
			(effects
				(font
					(size 1.27 1.27)
					(thickness 0.15)
				)
				(justify left bottom)
				(hide yes)
			)
		)
		(property "Footprint" "antmicro-footprints:C_0402_1005Metric"
			(at 316.23 124.46 0)
			(effects
				(font
					(size 1.27 1.27)
					(thickness 0.15)
				)
				(justify left bottom)
				(hide yes)
			)
		)
		(property "Datasheet" "https://www.murata.com/products/productdetail?partno=GRM155R61H104KE14%23"
			(at 318.77 124.46 0)
			(effects
				(font
					(size 1.27 1.27)
					(thickness 0.15)
				)
				(justify left bottom)
				(hide yes)
			)
		)
		(property "Description" ""
			(at 303.53 104.14 0)
			(effects
				(font
					(size 1.27 1.27)
				)
				(hide yes)
			)
		)
		(property "MPN" "GRM155R61H104KE14D"
			(at 321.31 124.46 0)
			(effects
				(font
					(size 1.27 1.27)
					(thickness 0.15)
				)
				(justify left bottom)
				(hide yes)
			)
		)
		(property "Manufacturer" "Murata"
			(at 323.85 124.46 0)
			(effects
				(font
					(size 1.27 1.27)
					(thickness 0.15)
				)
				(justify left bottom)
				(hide yes)
			)
		)
		(property "License" "Apache-2.0"
			(at 326.39 124.46 0)
			(effects
				(font
					(size 1.27 1.27)
					(thickness 0.15)
				)
				(justify left bottom)
				(hide yes)
			)
		)
		(property "Author" "Antmicro"
			(at 328.93 124.46 0)
			(effects
				(font
					(size 1.27 1.27)
					(thickness 0.15)
				)
				(justify left bottom)
				(hide yes)
			)
		)
		(property "Val" "100n"
			(at 309.88 107.95 90)
			(effects
				(font
					(size 1.27 1.27)
					(thickness 0.15)
				)
				(justify left)
			)
		)
		(property "Voltage" "50V"
			(at 331.47 124.46 0)
			(effects
				(font
					(size 1.27 1.27)
				)
				(justify left bottom)
				(hide yes)
			)
		)
		(property "Dielectric" "X5R"
			(at 334.01 124.46 0)
			(effects
				(font
					(size 1.27 1.27)
				)
				(justify left bottom)
				(hide yes)
			)
		)
		(property "Public" "False"
			(at 336.55 124.46 0)
			(effects
				(font
					(size 1.27 1.27)
				)
				(justify left bottom)
				(hide yes)
			)
		)
		(pin "1"
		)
		(pin "2"
		)
		(instances
			(project "com-express-7-baseboard"
				(path ""
					(reference "C28")
					(unit 1)
				)
			)
		)
	)
	(symbol
		(lib_id "antmicroResistors0402:R_0R_0402")
		(at 160.02 260.35 90)
		(unit 1)
		(exclude_from_sim no)
		(in_bom yes)
		(on_board yes)
		(dnp no)
		(property "Reference" "R31"
			(at 158.75 255.27 90)
			(effects
				(font
					(size 1.27 1.27)
					(thickness 0.15)
				)
				(justify left)
			)
		)
		(property "Value" "R_0R_0402"
			(at 172.72 240.03 0)
			(effects
				(font
					(size 1.27 1.27)
					(thickness 0.15)
				)
				(justify left bottom)
				(hide yes)
			)
		)
		(property "Footprint" "antmicro-footprints:R_0402_1005Metric"
			(at 175.26 240.03 0)
			(effects
				(font
					(size 1.27 1.27)
					(thickness 0.15)
				)
				(justify left bottom)
				(hide yes)
			)
		)
		(property "Datasheet" "https://industrial.panasonic.com/cdbs/www-data/pdf/RDA0000/AOA0000C301.pdf"
			(at 177.8 240.03 0)
			(effects
				(font
					(size 1.27 1.27)
					(thickness 0.15)
				)
				(justify left bottom)
				(hide yes)
			)
		)
		(property "Description" ""
			(at 160.02 260.35 0)
			(effects
				(font
					(size 1.27 1.27)
				)
				(hide yes)
			)
		)
		(property "MPN" "ERJ2GE0R00X"
			(at 180.34 240.03 0)
			(effects
				(font
					(size 1.27 1.27)
					(thickness 0.15)
				)
				(justify left bottom)
				(hide yes)
			)
		)
		(property "Manufacturer" "Panasonic"
			(at 182.88 240.03 0)
			(effects
				(font
					(size 1.27 1.27)
					(thickness 0.15)
				)
				(justify left bottom)
				(hide yes)
			)
		)
		(property "License" "Apache-2.0"
			(at 185.42 240.03 0)
			(effects
				(font
					(size 1.27 1.27)
					(thickness 0.15)
				)
				(justify left bottom)
				(hide yes)
			)
		)
		(property "Author" "Antmicro"
			(at 187.96 240.03 0)
			(effects
				(font
					(size 1.27 1.27)
					(thickness 0.15)
				)
				(justify left bottom)
				(hide yes)
			)
		)
		(property "Val" "0R"
			(at 158.75 257.81 90)
			(effects
				(font
					(size 1.27 1.27)
					(thickness 0.15)
				)
				(justify left)
			)
		)
		(property "Tolerance" "~"
			(at 170.18 240.03 0)
			(effects
				(font
					(size 1.27 1.27)
				)
				(justify left bottom)
				(hide yes)
			)
		)
		(property "Current" "1A"
			(at 190.5 240.03 0)
			(effects
				(font
					(size 1.27 1.27)
					(thickness 0.15)
				)
				(justify left bottom)
				(hide yes)
			)
		)
		(property "Public" "False"
			(at 190.5 240.03 0)
			(effects
				(font
					(size 1.27 1.27)
				)
				(justify left bottom)
				(hide yes)
			)
		)
		(pin "2"
		)
		(pin "1"
		)
		(instances
			(project "com-express-7-baseboard"
				(path ""
					(reference "R31")
					(unit 1)
				)
			)
		)
	)
	(symbol
		(lib_id "antmicroTestPoints:TP_0.75mm_SMD")
		(at 233.68 81.28 180)
		(unit 1)
		(exclude_from_sim no)
		(in_bom no)
		(on_board yes)
		(dnp no)
		(property "Reference" "TP3"
			(at 224.79 81.28 0)
			(effects
				(font
					(size 1.27 1.27)
					(thickness 0.15)
				)
			)
		)
		(property "Value" "TP_0.75mm_SMD"
			(at 222.885 77.47 0)
			(effects
				(font
					(size 1.27 1.27)
					(thickness 0.15)
				)
				(justify left bottom)
				(hide yes)
			)
		)
		(property "Footprint" "antmicro-footprints:TP_SMD_0.75mm"
			(at 222.885 74.93 0)
			(effects
				(font
					(size 1.27 1.27)
					(thickness 0.15)
				)
				(justify left bottom)
				(hide yes)
			)
		)
		(property "Datasheet" ""
			(at 215.9 68.58 0)
			(effects
				(font
					(size 1.27 1.27)
					(thickness 0.15)
				)
				(justify left bottom)
				(hide yes)
			)
		)
		(property "Description" ""
			(at 233.68 81.28 0)
			(effects
				(font
					(size 1.27 1.27)
				)
				(hide yes)
			)
		)
		(property "MPN" ""
			(at 222.885 69.85 0)
			(effects
				(font
					(size 1.27 1.27)
					(thickness 0.15)
				)
				(justify left bottom)
				(hide yes)
			)
		)
		(property "Manufacturer" ""
			(at 222.885 74.93 0)
			(effects
				(font
					(size 1.27 1.27)
					(thickness 0.15)
				)
				(justify left bottom)
				(hide yes)
			)
		)
		(property "Author" "Antmicro"
			(at 222.885 72.39 0)
			(effects
				(font
					(size 1.27 1.27)
					(thickness 0.15)
				)
				(justify left bottom)
				(hide yes)
			)
		)
		(property "License" "Apache-2.0"
			(at 222.885 69.85 0)
			(effects
				(font
					(size 1.27 1.27)
					(thickness 0.15)
				)
				(justify left bottom)
				(hide yes)
			)
		)
		(property "Public" "False"
			(at 223.52 67.31 0)
			(effects
				(font
					(size 1.27 1.27)
				)
				(justify left bottom)
				(hide yes)
			)
		)
		(pin "1"
		)
		(instances
			(project "com-express-7-baseboard"
				(path ""
					(reference "TP3")
					(unit 1)
				)
			)
		)
	)
	(symbol
		(lib_id "antmicropower:GND")
		(at 347.98 114.3 0)
		(mirror y)
		(unit 1)
		(exclude_from_sim no)
		(in_bom yes)
		(on_board yes)
		(dnp no)
		(property "Reference" "#PWR0455"
			(at 339.09 116.84 0)
			(effects
				(font
					(size 1.27 1.27)
					(thickness 0.15)
				)
				(justify left bottom)
				(hide yes)
			)
		)
		(property "Value" "GND"
			(at 347.98 118.11 0)
			(effects
				(font
					(size 1.27 1.27)
					(thickness 0.15)
				)
			)
		)
		(property "Footprint" ""
			(at 339.09 121.92 0)
			(effects
				(font
					(size 1.27 1.27)
					(thickness 0.15)
				)
				(justify left bottom)
				(hide yes)
			)
		)
		(property "Datasheet" ""
			(at 339.09 127 0)
			(effects
				(font
					(size 1.27 1.27)
					(thickness 0.15)
				)
				(justify left bottom)
				(hide yes)
			)
		)
		(property "Description" ""
			(at 347.98 114.3 0)
			(effects
				(font
					(size 1.27 1.27)
				)
				(hide yes)
			)
		)
		(property "Author" "Antmicro"
			(at 339.09 121.92 0)
			(effects
				(font
					(size 1.27 1.27)
					(thickness 0.15)
				)
				(justify left bottom)
				(hide yes)
			)
		)
		(property "License" "Apache-2.0"
			(at 339.09 124.46 0)
			(effects
				(font
					(size 1.27 1.27)
					(thickness 0.15)
				)
				(justify left bottom)
				(hide yes)
			)
		)
		(pin "1"
		)
		(instances
			(project "com-express-7-baseboard"
				(path ""
					(reference "#PWR0455")
					(unit 1)
				)
			)
		)
	)
	(symbol
		(lib_id "antmicropower:GND")
		(at 290.83 105.41 0)
		(unit 1)
		(exclude_from_sim no)
		(in_bom yes)
		(on_board yes)
		(dnp no)
		(property "Reference" "#PWR050"
			(at 299.72 107.95 0)
			(effects
				(font
					(size 1.27 1.27)
					(thickness 0.15)
				)
				(justify left bottom)
				(hide yes)
			)
		)
		(property "Value" "GND"
			(at 290.83 109.22 0)
			(effects
				(font
					(size 1.27 1.27)
					(thickness 0.15)
				)
			)
		)
		(property "Footprint" ""
			(at 299.72 113.03 0)
			(effects
				(font
					(size 1.27 1.27)
					(thickness 0.15)
				)
				(justify left bottom)
				(hide yes)
			)
		)
		(property "Datasheet" ""
			(at 299.72 118.11 0)
			(effects
				(font
					(size 1.27 1.27)
					(thickness 0.15)
				)
				(justify left bottom)
				(hide yes)
			)
		)
		(property "Description" ""
			(at 290.83 105.41 0)
			(effects
				(font
					(size 1.27 1.27)
				)
				(hide yes)
			)
		)
		(property "Author" "Antmicro"
			(at 299.72 113.03 0)
			(effects
				(font
					(size 1.27 1.27)
					(thickness 0.15)
				)
				(justify left bottom)
				(hide yes)
			)
		)
		(property "License" "Apache-2.0"
			(at 299.72 115.57 0)
			(effects
				(font
					(size 1.27 1.27)
					(thickness 0.15)
				)
				(justify left bottom)
				(hide yes)
			)
		)
		(pin "1"
		)
		(instances
			(project "com-express-7-baseboard"
				(path ""
					(reference "#PWR050")
					(unit 1)
				)
			)
		)
	)
	(symbol
		(lib_id "antmicroLEDIndicationDiscrete:LED_G_0603_LTST-C190GKT")
		(at 344.17 76.2 270)
		(mirror x)
		(unit 1)
		(exclude_from_sim no)
		(in_bom yes)
		(on_board yes)
		(dnp no)
		(fields_autoplaced yes)
		(property "Reference" "D8"
			(at 347.98 72.39 90)
			(effects
				(font
					(size 1.27 1.27)
				)
				(justify left)
			)
		)
		(property "Value" "LED_G_0603_LTST-C190GKT"
			(at 336.55 53.34 0)
			(effects
				(font
					(size 1.27 1.27)
					(thickness 0.15)
				)
				(justify left bottom)
				(hide yes)
			)
		)
		(property "Footprint" "antmicro-footprints:LED_0603_1608Metric_G"
			(at 334.01 53.34 0)
			(effects
				(font
					(size 1.27 1.27)
					(thickness 0.15)
				)
				(justify left bottom)
				(hide yes)
			)
		)
		(property "Datasheet" "https://media.digikey.com/pdf/Data%20Sheets/Lite-On%20PDFs/LTST-C190GKT.pdf"
			(at 331.47 53.34 0)
			(effects
				(font
					(size 1.27 1.27)
					(thickness 0.15)
				)
				(justify left bottom)
				(hide yes)
			)
		)
		(property "Description" ""
			(at 344.17 76.2 0)
			(effects
				(font
					(size 1.27 1.27)
				)
				(hide yes)
			)
		)
		(property "MPN" "LTST-C190GKT"
			(at 347.98 71.1201 90)
			(effects
				(font
					(size 1.27 1.27)
					(thickness 0.15)
				)
				(justify left)
				(hide yes)
			)
		)
		(property "Manufacturer" "Lite-On"
			(at 326.39 53.34 0)
			(effects
				(font
					(size 1.27 1.27)
					(thickness 0.15)
				)
				(justify left bottom)
				(hide yes)
			)
		)
		(property "Author" "Antmicro"
			(at 323.85 53.34 0)
			(effects
				(font
					(size 1.27 1.27)
					(thickness 0.15)
				)
				(justify left bottom)
				(hide yes)
			)
		)
		(property "License" "Apache-2.0"
			(at 321.31 53.34 0)
			(effects
				(font
					(size 1.27 1.27)
					(thickness 0.15)
				)
				(justify left bottom)
				(hide yes)
			)
		)
		(property "Public" "False"
			(at 326.39 55.88 0)
			(effects
				(font
					(size 1.27 1.27)
				)
				(justify left bottom)
				(hide yes)
			)
		)
		(property "Color" "Green"
			(at 347.98 74.93 90)
			(effects
				(font
					(size 1.27 1.27)
				)
				(justify left)
			)
		)
		(pin "1"
		)
		(pin "2"
		)
		(instances
			(project "com-express-7-baseboard"
				(path ""
					(reference "D8")
					(unit 1)
				)
			)
		)
	)
	(symbol
		(lib_id "antmicroResistors0402:R_220R_0402")
		(at 344.17 85.09 90)
		(unit 1)
		(exclude_from_sim no)
		(in_bom yes)
		(on_board yes)
		(dnp no)
		(property "Reference" "R65"
			(at 345.44 81.28 90)
			(effects
				(font
					(size 1.27 1.27)
					(thickness 0.15)
				)
				(justify right)
			)
		)
		(property "Value" "R_220R_0402"
			(at 356.87 64.77 0)
			(effects
				(font
					(size 1.27 1.27)
					(thickness 0.15)
				)
				(justify left bottom)
				(hide yes)
			)
		)
		(property "Footprint" "antmicro-footprints:R_0402_1005Metric"
			(at 359.41 64.77 0)
			(effects
				(font
					(size 1.27 1.27)
					(thickness 0.15)
				)
				(justify left bottom)
				(hide yes)
			)
		)
		(property "Datasheet" "https://www.bourns.com/docs/product-datasheets/cr.pdf"
			(at 361.95 64.77 0)
			(effects
				(font
					(size 1.27 1.27)
					(thickness 0.15)
				)
				(justify left bottom)
				(hide yes)
			)
		)
		(property "Description" ""
			(at 344.17 85.09 0)
			(effects
				(font
					(size 1.27 1.27)
				)
				(hide yes)
			)
		)
		(property "MPN" "CR0402-FX-2200GLF"
			(at 364.49 64.77 0)
			(effects
				(font
					(size 1.27 1.27)
					(thickness 0.15)
				)
				(justify left bottom)
				(hide yes)
			)
		)
		(property "Manufacturer" "Bourns"
			(at 367.03 64.77 0)
			(effects
				(font
					(size 1.27 1.27)
					(thickness 0.15)
				)
				(justify left bottom)
				(hide yes)
			)
		)
		(property "License" "Apache-2.0"
			(at 369.57 64.77 0)
			(effects
				(font
					(size 1.27 1.27)
					(thickness 0.15)
				)
				(justify left bottom)
				(hide yes)
			)
		)
		(property "Author" "Antmicro"
			(at 372.11 64.77 0)
			(effects
				(font
					(size 1.27 1.27)
					(thickness 0.15)
				)
				(justify left bottom)
				(hide yes)
			)
		)
		(property "Val" "220R"
			(at 345.44 83.82 90)
			(effects
				(font
					(size 1.27 1.27)
					(thickness 0.15)
				)
				(justify right)
			)
		)
		(property "Tolerance" "1%"
			(at 354.33 64.77 0)
			(effects
				(font
					(size 1.27 1.27)
				)
				(justify left bottom)
				(hide yes)
			)
		)
		(property "Public" "False"
			(at 374.65 64.77 0)
			(effects
				(font
					(size 1.27 1.27)
				)
				(justify left bottom)
				(hide yes)
			)
		)
		(pin "2"
		)
		(pin "1"
		)
		(instances
			(project "com-express-7-baseboard"
				(path ""
					(reference "R65")
					(unit 1)
				)
			)
		)
	)
	(symbol
		(lib_id "antmicropower:GND")
		(at 312.42 114.3 0)
		(mirror y)
		(unit 1)
		(exclude_from_sim no)
		(in_bom yes)
		(on_board yes)
		(dnp no)
		(property "Reference" "#PWR0451"
			(at 303.53 116.84 0)
			(effects
				(font
					(size 1.27 1.27)
					(thickness 0.15)
				)
				(justify left bottom)
				(hide yes)
			)
		)
		(property "Value" "GND"
			(at 312.42 118.11 0)
			(effects
				(font
					(size 1.27 1.27)
					(thickness 0.15)
				)
			)
		)
		(property "Footprint" ""
			(at 303.53 121.92 0)
			(effects
				(font
					(size 1.27 1.27)
					(thickness 0.15)
				)
				(justify left bottom)
				(hide yes)
			)
		)
		(property "Datasheet" ""
			(at 303.53 127 0)
			(effects
				(font
					(size 1.27 1.27)
					(thickness 0.15)
				)
				(justify left bottom)
				(hide yes)
			)
		)
		(property "Description" ""
			(at 312.42 114.3 0)
			(effects
				(font
					(size 1.27 1.27)
				)
				(hide yes)
			)
		)
		(property "Author" "Antmicro"
			(at 303.53 121.92 0)
			(effects
				(font
					(size 1.27 1.27)
					(thickness 0.15)
				)
				(justify left bottom)
				(hide yes)
			)
		)
		(property "License" "Apache-2.0"
			(at 303.53 124.46 0)
			(effects
				(font
					(size 1.27 1.27)
					(thickness 0.15)
				)
				(justify left bottom)
				(hide yes)
			)
		)
		(pin "1"
		)
		(instances
			(project "com-express-7-baseboard"
				(path ""
					(reference "#PWR0451")
					(unit 1)
				)
			)
		)
	)
	(symbol
		(lib_id "antmicroResistors0402:R_0R_0402")
		(at 168.91 233.68 0)
		(unit 1)
		(exclude_from_sim no)
		(in_bom yes)
		(on_board yes)
		(dnp no)
		(property "Reference" "R33"
			(at 166.37 232.41 0)
			(effects
				(font
					(size 1.27 1.27)
					(thickness 0.15)
				)
			)
		)
		(property "Value" "R_0R_0402"
			(at 189.23 246.38 0)
			(effects
				(font
					(size 1.27 1.27)
					(thickness 0.15)
				)
				(justify left bottom)
				(hide yes)
			)
		)
		(property "Footprint" "antmicro-footprints:R_0402_1005Metric"
			(at 189.23 248.92 0)
			(effects
				(font
					(size 1.27 1.27)
					(thickness 0.15)
				)
				(justify left bottom)
				(hide yes)
			)
		)
		(property "Datasheet" "https://industrial.panasonic.com/cdbs/www-data/pdf/RDA0000/AOA0000C301.pdf"
			(at 189.23 251.46 0)
			(effects
				(font
					(size 1.27 1.27)
					(thickness 0.15)
				)
				(justify left bottom)
				(hide yes)
			)
		)
		(property "Description" ""
			(at 168.91 233.68 0)
			(effects
				(font
					(size 1.27 1.27)
				)
				(hide yes)
			)
		)
		(property "MPN" "ERJ2GE0R00X"
			(at 189.23 254 0)
			(effects
				(font
					(size 1.27 1.27)
					(thickness 0.15)
				)
				(justify left bottom)
				(hide yes)
			)
		)
		(property "Manufacturer" "Panasonic"
			(at 189.23 256.54 0)
			(effects
				(font
					(size 1.27 1.27)
					(thickness 0.15)
				)
				(justify left bottom)
				(hide yes)
			)
		)
		(property "License" "Apache-2.0"
			(at 189.23 259.08 0)
			(effects
				(font
					(size 1.27 1.27)
					(thickness 0.15)
				)
				(justify left bottom)
				(hide yes)
			)
		)
		(property "Author" "Antmicro"
			(at 189.23 261.62 0)
			(effects
				(font
					(size 1.27 1.27)
					(thickness 0.15)
				)
				(justify left bottom)
				(hide yes)
			)
		)
		(property "Val" "0R"
			(at 175.26 232.41 0)
			(effects
				(font
					(size 1.27 1.27)
					(thickness 0.15)
				)
			)
		)
		(property "Tolerance" "~"
			(at 189.23 243.84 0)
			(effects
				(font
					(size 1.27 1.27)
				)
				(justify left bottom)
				(hide yes)
			)
		)
		(property "Current" "1A"
			(at 189.23 264.16 0)
			(effects
				(font
					(size 1.27 1.27)
					(thickness 0.15)
				)
				(justify left bottom)
				(hide yes)
			)
		)
		(property "Public" "False"
			(at 189.23 264.16 0)
			(effects
				(font
					(size 1.27 1.27)
				)
				(justify left bottom)
				(hide yes)
			)
		)
		(pin "2"
		)
		(pin "1"
		)
		(instances
			(project "com-express-7-baseboard"
				(path ""
					(reference "R33")
					(unit 1)
				)
			)
		)
	)
	(symbol
		(lib_id "antmicroResistors0402:R_0R_0402")
		(at 168.91 251.46 0)
		(unit 1)
		(exclude_from_sim no)
		(in_bom yes)
		(on_board yes)
		(dnp no)
		(property "Reference" "R35"
			(at 167.64 250.19 0)
			(effects
				(font
					(size 1.27 1.27)
					(thickness 0.15)
				)
			)
		)
		(property "Value" "R_0R_0402"
			(at 189.23 264.16 0)
			(effects
				(font
					(size 1.27 1.27)
					(thickness 0.15)
				)
				(justify left bottom)
				(hide yes)
			)
		)
		(property "Footprint" "antmicro-footprints:R_0402_1005Metric"
			(at 189.23 266.7 0)
			(effects
				(font
					(size 1.27 1.27)
					(thickness 0.15)
				)
				(justify left bottom)
				(hide yes)
			)
		)
		(property "Datasheet" "https://industrial.panasonic.com/cdbs/www-data/pdf/RDA0000/AOA0000C301.pdf"
			(at 189.23 269.24 0)
			(effects
				(font
					(size 1.27 1.27)
					(thickness 0.15)
				)
				(justify left bottom)
				(hide yes)
			)
		)
		(property "Description" ""
			(at 168.91 251.46 0)
			(effects
				(font
					(size 1.27 1.27)
				)
				(hide yes)
			)
		)
		(property "MPN" "ERJ2GE0R00X"
			(at 189.23 271.78 0)
			(effects
				(font
					(size 1.27 1.27)
					(thickness 0.15)
				)
				(justify left bottom)
				(hide yes)
			)
		)
		(property "Manufacturer" "Panasonic"
			(at 189.23 274.32 0)
			(effects
				(font
					(size 1.27 1.27)
					(thickness 0.15)
				)
				(justify left bottom)
				(hide yes)
			)
		)
		(property "License" "Apache-2.0"
			(at 189.23 276.86 0)
			(effects
				(font
					(size 1.27 1.27)
					(thickness 0.15)
				)
				(justify left bottom)
				(hide yes)
			)
		)
		(property "Author" "Antmicro"
			(at 189.23 279.4 0)
			(effects
				(font
					(size 1.27 1.27)
					(thickness 0.15)
				)
				(justify left bottom)
				(hide yes)
			)
		)
		(property "Val" "0R"
			(at 175.26 250.19 0)
			(effects
				(font
					(size 1.27 1.27)
					(thickness 0.15)
				)
			)
		)
		(property "Tolerance" "~"
			(at 189.23 261.62 0)
			(effects
				(font
					(size 1.27 1.27)
				)
				(justify left bottom)
				(hide yes)
			)
		)
		(property "Current" "1A"
			(at 189.23 281.94 0)
			(effects
				(font
					(size 1.27 1.27)
					(thickness 0.15)
				)
				(justify left bottom)
				(hide yes)
			)
		)
		(property "Public" "False"
			(at 189.23 281.94 0)
			(effects
				(font
					(size 1.27 1.27)
				)
				(justify left bottom)
				(hide yes)
			)
		)
		(pin "1"
		)
		(pin "2"
		)
		(instances
			(project "com-express-7-baseboard"
				(path ""
					(reference "R35")
					(unit 1)
				)
			)
		)
	)
	(symbol
		(lib_id "antmicroResistors0402:R_0R_0402")
		(at 168.91 236.22 0)
		(unit 1)
		(exclude_from_sim no)
		(in_bom yes)
		(on_board yes)
		(dnp no)
		(property "Reference" "R34"
			(at 166.37 234.95 0)
			(effects
				(font
					(size 1.27 1.27)
					(thickness 0.15)
				)
			)
		)
		(property "Value" "R_0R_0402"
			(at 189.23 248.92 0)
			(effects
				(font
					(size 1.27 1.27)
					(thickness 0.15)
				)
				(justify left bottom)
				(hide yes)
			)
		)
		(property "Footprint" "antmicro-footprints:R_0402_1005Metric"
			(at 189.23 251.46 0)
			(effects
				(font
					(size 1.27 1.27)
					(thickness 0.15)
				)
				(justify left bottom)
				(hide yes)
			)
		)
		(property "Datasheet" "https://industrial.panasonic.com/cdbs/www-data/pdf/RDA0000/AOA0000C301.pdf"
			(at 189.23 254 0)
			(effects
				(font
					(size 1.27 1.27)
					(thickness 0.15)
				)
				(justify left bottom)
				(hide yes)
			)
		)
		(property "Description" ""
			(at 168.91 236.22 0)
			(effects
				(font
					(size 1.27 1.27)
				)
				(hide yes)
			)
		)
		(property "MPN" "ERJ2GE0R00X"
			(at 189.23 256.54 0)
			(effects
				(font
					(size 1.27 1.27)
					(thickness 0.15)
				)
				(justify left bottom)
				(hide yes)
			)
		)
		(property "Manufacturer" "Panasonic"
			(at 189.23 259.08 0)
			(effects
				(font
					(size 1.27 1.27)
					(thickness 0.15)
				)
				(justify left bottom)
				(hide yes)
			)
		)
		(property "License" "Apache-2.0"
			(at 189.23 261.62 0)
			(effects
				(font
					(size 1.27 1.27)
					(thickness 0.15)
				)
				(justify left bottom)
				(hide yes)
			)
		)
		(property "Author" "Antmicro"
			(at 189.23 264.16 0)
			(effects
				(font
					(size 1.27 1.27)
					(thickness 0.15)
				)
				(justify left bottom)
				(hide yes)
			)
		)
		(property "Val" "0R"
			(at 175.26 234.95 0)
			(effects
				(font
					(size 1.27 1.27)
					(thickness 0.15)
				)
			)
		)
		(property "Tolerance" "~"
			(at 189.23 246.38 0)
			(effects
				(font
					(size 1.27 1.27)
				)
				(justify left bottom)
				(hide yes)
			)
		)
		(property "Current" "1A"
			(at 189.23 266.7 0)
			(effects
				(font
					(size 1.27 1.27)
					(thickness 0.15)
				)
				(justify left bottom)
				(hide yes)
			)
		)
		(property "Public" "False"
			(at 189.23 266.7 0)
			(effects
				(font
					(size 1.27 1.27)
				)
				(justify left bottom)
				(hide yes)
			)
		)
		(pin "2"
		)
		(pin "1"
		)
		(instances
			(project "com-express-7-baseboard"
				(path ""
					(reference "R34")
					(unit 1)
				)
			)
		)
	)
	(symbol
		(lib_id "antmicroCapacitors0402:C_100n_0402")
		(at 321.31 104.14 90)
		(mirror x)
		(unit 1)
		(exclude_from_sim no)
		(in_bom yes)
		(on_board yes)
		(dnp no)
		(property "Reference" "C209"
			(at 327.66 105.41 90)
			(effects
				(font
					(size 1.27 1.27)
					(thickness 0.15)
				)
				(justify left)
			)
		)
		(property "Value" "C_100n_0402"
			(at 331.47 124.46 0)
			(effects
				(font
					(size 1.27 1.27)
					(thickness 0.15)
				)
				(justify left bottom)
				(hide yes)
			)
		)
		(property "Footprint" "antmicro-footprints:C_0402_1005Metric"
			(at 334.01 124.46 0)
			(effects
				(font
					(size 1.27 1.27)
					(thickness 0.15)
				)
				(justify left bottom)
				(hide yes)
			)
		)
		(property "Datasheet" "https://www.murata.com/products/productdetail?partno=GRM155R61H104KE14%23"
			(at 336.55 124.46 0)
			(effects
				(font
					(size 1.27 1.27)
					(thickness 0.15)
				)
				(justify left bottom)
				(hide yes)
			)
		)
		(property "Description" ""
			(at 321.31 104.14 0)
			(effects
				(font
					(size 1.27 1.27)
				)
				(hide yes)
			)
		)
		(property "MPN" "GRM155R61H104KE14D"
			(at 339.09 124.46 0)
			(effects
				(font
					(size 1.27 1.27)
					(thickness 0.15)
				)
				(justify left bottom)
				(hide yes)
			)
		)
		(property "Manufacturer" "Murata"
			(at 341.63 124.46 0)
			(effects
				(font
					(size 1.27 1.27)
					(thickness 0.15)
				)
				(justify left bottom)
				(hide yes)
			)
		)
		(property "License" "Apache-2.0"
			(at 344.17 124.46 0)
			(effects
				(font
					(size 1.27 1.27)
					(thickness 0.15)
				)
				(justify left bottom)
				(hide yes)
			)
		)
		(property "Author" "Antmicro"
			(at 346.71 124.46 0)
			(effects
				(font
					(size 1.27 1.27)
					(thickness 0.15)
				)
				(justify left bottom)
				(hide yes)
			)
		)
		(property "Val" "100n"
			(at 327.66 107.95 90)
			(effects
				(font
					(size 1.27 1.27)
					(thickness 0.15)
				)
				(justify left)
			)
		)
		(property "Voltage" "50V"
			(at 349.25 124.46 0)
			(effects
				(font
					(size 1.27 1.27)
				)
				(justify left bottom)
				(hide yes)
			)
		)
		(property "Dielectric" "X5R"
			(at 351.79 124.46 0)
			(effects
				(font
					(size 1.27 1.27)
				)
				(justify left bottom)
				(hide yes)
			)
		)
		(property "Public" "False"
			(at 354.33 124.46 0)
			(effects
				(font
					(size 1.27 1.27)
				)
				(justify left bottom)
				(hide yes)
			)
		)
		(pin "1"
		)
		(pin "2"
		)
		(instances
			(project "com-express-7-baseboard"
				(path ""
					(reference "C209")
					(unit 1)
				)
			)
		)
	)
	(symbol
		(lib_id "antmicropower:GND")
		(at 330.2 114.3 0)
		(mirror y)
		(unit 1)
		(exclude_from_sim no)
		(in_bom yes)
		(on_board yes)
		(dnp no)
		(property "Reference" "#PWR0453"
			(at 321.31 116.84 0)
			(effects
				(font
					(size 1.27 1.27)
					(thickness 0.15)
				)
				(justify left bottom)
				(hide yes)
			)
		)
		(property "Value" "GND"
			(at 330.2 118.11 0)
			(effects
				(font
					(size 1.27 1.27)
					(thickness 0.15)
				)
			)
		)
		(property "Footprint" ""
			(at 321.31 121.92 0)
			(effects
				(font
					(size 1.27 1.27)
					(thickness 0.15)
				)
				(justify left bottom)
				(hide yes)
			)
		)
		(property "Datasheet" ""
			(at 321.31 127 0)
			(effects
				(font
					(size 1.27 1.27)
					(thickness 0.15)
				)
				(justify left bottom)
				(hide yes)
			)
		)
		(property "Description" ""
			(at 330.2 114.3 0)
			(effects
				(font
					(size 1.27 1.27)
				)
				(hide yes)
			)
		)
		(property "Author" "Antmicro"
			(at 321.31 121.92 0)
			(effects
				(font
					(size 1.27 1.27)
					(thickness 0.15)
				)
				(justify left bottom)
				(hide yes)
			)
		)
		(property "License" "Apache-2.0"
			(at 321.31 124.46 0)
			(effects
				(font
					(size 1.27 1.27)
					(thickness 0.15)
				)
				(justify left bottom)
				(hide yes)
			)
		)
		(pin "1"
		)
		(instances
			(project "com-express-7-baseboard"
				(path ""
					(reference "#PWR0453")
					(unit 1)
				)
			)
		)
	)
	(symbol
		(lib_id "antmicroWire2BoardConnectors:Bel-Fuse_SFP+_2x20_SS-79100-010")
		(at 261.62 60.96 0)
		(unit 1)
		(exclude_from_sim no)
		(in_bom yes)
		(on_board yes)
		(dnp no)
		(fields_autoplaced yes)
		(property "Reference" "J2"
			(at 275.59 53.34 0)
			(effects
				(font
					(size 1.27 1.27)
					(thickness 0.15)
				)
			)
		)
		(property "Value" "Bel-Fuse_SFP+_2x20_SS-79100-010"
			(at 303.53 71.12 0)
			(effects
				(font
					(size 1.27 1.27)
					(thickness 0.15)
				)
				(justify left bottom)
				(hide yes)
			)
		)
		(property "Footprint" "antmicro-footprints:Conn_Bel-Fuse_SFP+_2x20_SS-79100-010"
			(at 303.53 73.66 0)
			(effects
				(font
					(size 1.27 1.27)
					(thickness 0.15)
				)
				(justify left bottom)
				(hide yes)
			)
		)
		(property "Datasheet" "https://www.belfuse.com/resources/datasheets/stewartconnector/ds-STW-SFP-cages.pdf"
			(at 303.53 76.2 0)
			(effects
				(font
					(size 1.27 1.27)
					(thickness 0.15)
				)
				(justify left bottom)
				(hide yes)
			)
		)
		(property "Description" ""
			(at 261.62 60.96 0)
			(effects
				(font
					(size 1.27 1.27)
				)
				(hide yes)
			)
		)
		(property "MPN" "SS-79100-010"
			(at 275.59 55.88 0)
			(effects
				(font
					(size 1.27 1.27)
					(thickness 0.15)
				)
			)
		)
		(property "Manufacturer" "Bel Fuse"
			(at 303.53 68.58 0)
			(effects
				(font
					(size 1.27 1.27)
					(thickness 0.15)
				)
				(justify left bottom)
				(hide yes)
			)
		)
		(property "Author" "Antmicro"
			(at 303.53 78.74 0)
			(effects
				(font
					(size 1.27 1.27)
					(thickness 0.15)
				)
				(justify left bottom)
				(hide yes)
			)
		)
		(property "License" "Apache-2.0"
			(at 303.53 81.28 0)
			(effects
				(font
					(size 1.27 1.27)
					(thickness 0.15)
				)
				(justify left bottom)
				(hide yes)
			)
		)
		(pin "T6"
		)
		(pin "T4"
		)
		(pin "T10"
		)
		(pin "L12"
		)
		(pin "L11"
		)
		(pin "T5"
		)
		(pin "L13"
		)
		(pin "L19"
		)
		(pin "L2"
		)
		(pin "L9"
		)
		(pin "T3"
		)
		(pin "T9"
		)
		(pin "L7"
		)
		(pin "T19"
		)
		(pin "L18"
		)
		(pin "L5"
		)
		(pin "L14"
		)
		(pin "L10"
		)
		(pin "L16"
		)
		(pin "L17"
		)
		(pin "L20"
		)
		(pin "T18"
		)
		(pin "T17"
		)
		(pin "T16"
		)
		(pin "L15"
		)
		(pin "L1"
		)
		(pin "L8"
		)
		(pin "T2"
		)
		(pin "T14"
		)
		(pin "L3"
		)
		(pin "L6"
		)
		(pin "T20"
		)
		(pin "T8"
		)
		(pin "T1"
		)
		(pin "SH"
		)
		(pin "L4"
		)
		(pin "T7"
		)
		(pin "T11"
		)
		(pin "T12"
		)
		(pin "T13"
		)
		(pin "T15"
		)
		(instances
			(project "com-express-7-baseboard"
				(path ""
					(reference "J2")
					(unit 1)
				)
			)
		)
	)
	(symbol
		(lib_id "antmicropower:+3V3")
		(at 232.41 34.29 0)
		(unit 1)
		(exclude_from_sim no)
		(in_bom yes)
		(on_board yes)
		(dnp no)
		(fields_autoplaced yes)
		(property "Reference" "#PWR040"
			(at 247.65 34.29 0)
			(effects
				(font
					(size 1.27 1.27)
					(thickness 0.15)
				)
				(justify left bottom)
				(hide yes)
			)
		)
		(property "Value" "+3V3"
			(at 232.41 29.21 0)
			(effects
				(font
					(size 1.27 1.27)
					(thickness 0.15)
				)
			)
		)
		(property "Footprint" ""
			(at 247.65 41.91 0)
			(effects
				(font
					(size 1.27 1.27)
					(thickness 0.15)
				)
				(justify left bottom)
				(hide yes)
			)
		)
		(property "Datasheet" ""
			(at 247.65 44.45 0)
			(effects
				(font
					(size 1.27 1.27)
					(thickness 0.15)
				)
				(justify left bottom)
				(hide yes)
			)
		)
		(property "Description" ""
			(at 232.41 34.29 0)
			(effects
				(font
					(size 1.27 1.27)
				)
				(hide yes)
			)
		)
		(property "Author" "Antmicro"
			(at 247.65 36.83 0)
			(effects
				(font
					(size 1.27 1.27)
					(thickness 0.15)
				)
				(justify left bottom)
				(hide yes)
			)
		)
		(property "License" "Apache-2.0"
			(at 247.65 39.37 0)
			(effects
				(font
					(size 1.27 1.27)
					(thickness 0.15)
				)
				(justify left bottom)
				(hide yes)
			)
		)
		(pin "1"
		)
		(instances
			(project "com-express-7-baseboard"
				(path ""
					(reference "#PWR040")
					(unit 1)
				)
			)
		)
	)
	(symbol
		(lib_id "antmicroCapacitors0603:C_22u_16V_0603")
		(at 232.41 41.91 90)
		(unit 1)
		(exclude_from_sim no)
		(in_bom yes)
		(on_board yes)
		(dnp no)
		(fields_autoplaced yes)
		(property "Reference" "C22"
			(at 234.95 38.0935 90)
			(effects
				(font
					(size 1.27 1.27)
					(thickness 0.15)
				)
				(justify right)
			)
		)
		(property "Value" "C_22u_16V_0603"
			(at 242.57 21.59 0)
			(effects
				(font
					(size 1.27 1.27)
					(thickness 0.15)
				)
				(justify left bottom)
				(hide yes)
			)
		)
		(property "Footprint" "antmicro-footprints:C_0603_1608Metric"
			(at 245.11 21.59 0)
			(effects
				(font
					(size 1.27 1.27)
					(thickness 0.15)
				)
				(justify left bottom)
				(hide yes)
			)
		)
		(property "Datasheet" "https://product.samsungsem.com/mlcc/CL10A226MO7JZN.do"
			(at 247.65 21.59 0)
			(effects
				(font
					(size 1.27 1.27)
					(thickness 0.15)
				)
				(justify left bottom)
				(hide yes)
			)
		)
		(property "Description" ""
			(at 232.41 41.91 0)
			(effects
				(font
					(size 1.27 1.27)
				)
				(hide yes)
			)
		)
		(property "MPN" "CL10A226MO7JZNC"
			(at 250.19 21.59 0)
			(effects
				(font
					(size 1.27 1.27)
					(thickness 0.15)
				)
				(justify left bottom)
				(hide yes)
			)
		)
		(property "Manufacturer" "Samsung Electro-Mechanics"
			(at 252.73 21.59 0)
			(effects
				(font
					(size 1.27 1.27)
					(thickness 0.15)
				)
				(justify left bottom)
				(hide yes)
			)
		)
		(property "License" "Apache-2.0"
			(at 255.27 21.59 0)
			(effects
				(font
					(size 1.27 1.27)
					(thickness 0.15)
				)
				(justify left bottom)
				(hide yes)
			)
		)
		(property "Author" "Antmicro"
			(at 257.81 21.59 0)
			(effects
				(font
					(size 1.27 1.27)
					(thickness 0.15)
				)
				(justify left bottom)
				(hide yes)
			)
		)
		(property "Val" "22u"
			(at 234.95 40.6335 90)
			(effects
				(font
					(size 1.27 1.27)
					(thickness 0.15)
				)
				(justify right)
			)
		)
		(property "Voltage" "16V"
			(at 260.35 21.59 0)
			(effects
				(font
					(size 1.27 1.27)
				)
				(justify left bottom)
				(hide yes)
			)
		)
		(property "Dielectric" ""
			(at 262.89 21.59 0)
			(effects
				(font
					(size 1.27 1.27)
				)
				(justify left bottom)
				(hide yes)
			)
		)
		(property "Public" "False"
			(at 265.43 21.59 0)
			(effects
				(font
					(size 1.27 1.27)
				)
				(justify left bottom)
				(hide yes)
			)
		)
		(pin "2"
		)
		(pin "1"
		)
		(instances
			(project "com-express-7-baseboard"
				(path ""
					(reference "C22")
					(unit 1)
				)
			)
		)
	)
	(symbol
		(lib_id "antmicropower:+3V3")
		(at 344.17 69.85 0)
		(unit 1)
		(exclude_from_sim no)
		(in_bom yes)
		(on_board yes)
		(dnp no)
		(property "Reference" "#PWR056"
			(at 344.17 73.66 0)
			(effects
				(font
					(size 1.27 1.27)
				)
				(justify left bottom)
				(hide yes)
			)
		)
		(property "Value" "+3V3"
			(at 341.63 66.04 0)
			(effects
				(font
					(size 1.27 1.27)
				)
				(justify left)
			)
		)
		(property "Footprint" ""
			(at 344.17 69.85 0)
			(effects
				(font
					(size 1.27 1.27)
				)
				(justify left bottom)
				(hide yes)
			)
		)
		(property "Datasheet" ""
			(at 344.17 69.85 0)
			(effects
				(font
					(size 1.27 1.27)
				)
				(justify left bottom)
				(hide yes)
			)
		)
		(property "Description" ""
			(at 344.17 69.85 0)
			(effects
				(font
					(size 1.27 1.27)
				)
				(hide yes)
			)
		)
		(property "Author" "Antmicro"
			(at 359.41 72.39 0)
			(effects
				(font
					(size 1.27 1.27)
					(thickness 0.15)
				)
				(justify left bottom)
				(hide yes)
			)
		)
		(property "License" "Apache-2.0"
			(at 359.41 74.93 0)
			(effects
				(font
					(size 1.27 1.27)
					(thickness 0.15)
				)
				(justify left bottom)
				(hide yes)
			)
		)
		(pin "1"
		)
		(instances
			(project "com-express-7-baseboard"
				(path ""
					(reference "#PWR056")
					(unit 1)
				)
			)
		)
	)
	(symbol
		(lib_id "antmicroResistors0402:R_1k_0402")
		(at 227.33 63.5 90)
		(unit 1)
		(exclude_from_sim no)
		(in_bom yes)
		(on_board yes)
		(dnp no)
		(property "Reference" "R49"
			(at 228.6 59.69 90)
			(effects
				(font
					(size 1.27 1.27)
					(thickness 0.15)
				)
				(justify right)
			)
		)
		(property "Value" "R_1k_0402"
			(at 240.03 43.18 0)
			(effects
				(font
					(size 1.27 1.27)
					(thickness 0.15)
				)
				(justify left bottom)
				(hide yes)
			)
		)
		(property "Footprint" "antmicro-footprints:R_0402_1005Metric"
			(at 242.57 43.18 0)
			(effects
				(font
					(size 1.27 1.27)
					(thickness 0.15)
				)
				(justify left bottom)
				(hide yes)
			)
		)
		(property "Datasheet" "https://www.bourns.com/docs/product-datasheets/cr.pdf"
			(at 245.11 43.18 0)
			(effects
				(font
					(size 1.27 1.27)
					(thickness 0.15)
				)
				(justify left bottom)
				(hide yes)
			)
		)
		(property "Description" ""
			(at 227.33 63.5 0)
			(effects
				(font
					(size 1.27 1.27)
				)
				(hide yes)
			)
		)
		(property "MPN" "CR0402-FX-1001GLF"
			(at 247.65 43.18 0)
			(effects
				(font
					(size 1.27 1.27)
					(thickness 0.15)
				)
				(justify left bottom)
				(hide yes)
			)
		)
		(property "Manufacturer" "Bourns"
			(at 250.19 43.18 0)
			(effects
				(font
					(size 1.27 1.27)
					(thickness 0.15)
				)
				(justify left bottom)
				(hide yes)
			)
		)
		(property "License" "Apache-2.0"
			(at 252.73 43.18 0)
			(effects
				(font
					(size 1.27 1.27)
					(thickness 0.15)
				)
				(justify left bottom)
				(hide yes)
			)
		)
		(property "Author" "Antmicro"
			(at 255.27 43.18 0)
			(effects
				(font
					(size 1.27 1.27)
					(thickness 0.15)
				)
				(justify left bottom)
				(hide yes)
			)
		)
		(property "Val" "1k"
			(at 228.6 62.23 90)
			(effects
				(font
					(size 1.27 1.27)
					(thickness 0.15)
				)
				(justify right)
			)
		)
		(property "Tolerance" "1%"
			(at 237.49 43.18 0)
			(effects
				(font
					(size 1.27 1.27)
				)
				(justify left bottom)
				(hide yes)
			)
		)
		(property "Public" "False"
			(at 257.81 43.18 0)
			(effects
				(font
					(size 1.27 1.27)
				)
				(justify left bottom)
				(hide yes)
			)
		)
		(pin "2"
		)
		(pin "1"
		)
		(instances
			(project "com-express-7-baseboard"
				(path ""
					(reference "R49")
					(unit 1)
				)
			)
		)
	)
	(sheet
		(at 152.4 162.56)
		(size 55.88 35.56)
		(exclude_from_sim no)
		(in_bom yes)
		(on_board yes)
		(dnp no)
		(fields_autoplaced yes)
		(stroke
			(width 0.1524)
			(type solid)
		)
		(fill
			(color 0 0 0 0.0000)
		)
		(property "Sheetname" "KR to SFI #2"
			(at 152.4 161.8484 0)
			(effects
				(font
					(size 1.27 1.27)
				)
				(justify left bottom)
			)
		)
		(property "Sheetfile" "kr_sfi.kicad_sch"
			(at 152.4 198.7046 0)
			(effects
				(font
					(size 1.27 1.27)
				)
				(justify left top)
			)
		)
		(pin "KR{10GBaseKR}" input
			(at 152.4 172.72 180)
			(effects
				(font
					(size 1.27 1.27)
				)
				(justify left)
			)
		)
		(pin "SFI{SFI}" input
			(at 208.28 172.72 0)
			(effects
				(font
					(size 1.27 1.27)
				)
				(justify right)
			)
		)
		(pin "PHY_RESET" input
			(at 152.4 189.23 180)
			(effects
				(font
					(size 1.27 1.27)
				)
				(justify left)
			)
		)
		(pin "MDIO{MDIO}" input
			(at 152.4 186.69 180)
			(effects
				(font
					(size 1.27 1.27)
				)
				(justify left)
			)
		)
		(instances
			(project "com-express-7-baseboard"
				(path ""
					(page "18")
				)
			)
		)
	)
	(sheet
		(at 152.4 78.74)
		(size 55.88 35.56)
		(exclude_from_sim no)
		(in_bom yes)
		(on_board yes)
		(dnp no)
		(fields_autoplaced yes)
		(stroke
			(width 0.1524)
			(type solid)
		)
		(fill
			(color 0 0 0 0.0000)
		)
		(property "Sheetname" "KR to SFI #1"
			(at 152.4 78.0284 0)
			(effects
				(font
					(size 1.27 1.27)
				)
				(justify left bottom)
			)
		)
		(property "Sheetfile" "kr_sfi.kicad_sch"
			(at 152.4 114.8846 0)
			(effects
				(font
					(size 1.27 1.27)
				)
				(justify left top)
			)
		)
		(pin "KR{10GBaseKR}" input
			(at 152.4 88.9 180)
			(effects
				(font
					(size 1.27 1.27)
				)
				(justify left)
			)
		)
		(pin "SFI{SFI}" input
			(at 208.28 88.9 0)
			(effects
				(font
					(size 1.27 1.27)
				)
				(justify right)
			)
		)
		(pin "PHY_RESET" input
			(at 152.4 105.41 180)
			(effects
				(font
					(size 1.27 1.27)
				)
				(justify left)
			)
		)
		(pin "MDIO{MDIO}" input
			(at 152.4 102.87 180)
			(effects
				(font
					(size 1.27 1.27)
				)
				(justify left)
			)
		)
		(instances
			(project "com-express-7-baseboard"
				(path ""
					(page "17")
				)
			)
		)
	)
)
